G04 ================== begin FILE IDENTIFICATION RECORD ==================*
G04 Layout Name:  12433-1M.brd*
G04 Film Name:    L3VCC*
G04 File Format:  Gerber RS274X*
G04 File Origin:  Cadence Allegro 16.2-S037*
G04 Origin Date:  Fri Dec 07 18:55:12 2012*
G04 *
G04 Layer:  VIA CLASS/L3VCC*
G04 Layer:  PIN/L3VCC*
G04 Layer:  PACKAGE GEOMETRY/PWRVCC*
G04 Layer:  ETCH/L3VCC*
G04 Layer:  DRAWING FORMAT/LAYER_PCB_STORY*
G04 Layer:  DRAWING FORMAT/LAYER_L3VCC*
G04 *
G04 Offset:    (0.00 0.00)*
G04 Mirror:    No*
G04 Mode:      Negative*
G04 Rotation:  0*
G04 FullContactRelief:  No*
G04 UndefLineWidth:     6.00*
G04 ================== end FILE IDENTIFICATION RECORD ====================*
%FSLAX35Y35*MOIN*%
%IR0*IPPOS*OFA0.00000B0.00000*MIA0B0*SFA1.00000B1.00000*%
%AMMACRO26*
4,1,17,-.09386,.06558,
-.103822,.048285,
-.110629,.029523,
-.114075,.009864,
-.114055,-.010095,
-.110569,-.029747,
-.103724,-.048495,
-.09386,-.06558,
-.09745,-.06917,
-.107981,-.051197,
-.115231,-.031669,
-.118979,-.011178,
-.119113,.009652,
-.115627,.030189,
-.108628,.049809,
-.098328,.067916,
-.09745,.06917,
-.09386,.06558,
90.*
4,1,17,-.06558,-.09386,
-.048285,-.103822,
-.029523,-.110629,
-.009864,-.114075,
.010095,-.114055,
.029747,-.110569,
.048495,-.103724,
.06558,-.09386,
.06917,-.09745,
.051197,-.107981,
.031669,-.115231,
.011178,-.118979,
-.009652,-.119113,
-.030189,-.115627,
-.049809,-.108628,
-.067916,-.098328,
-.06917,-.09745,
-.06558,-.09386,
90.*
4,1,17,.09386,-.06558,
.103822,-.048285,
.110629,-.029523,
.114075,-.009864,
.114055,.010095,
.110569,.029747,
.103724,.048495,
.09386,.06558,
.09745,.06917,
.107981,.051197,
.115231,.031669,
.118979,.011178,
.119113,-.009652,
.115627,-.030189,
.108628,-.049809,
.098328,-.067916,
.09745,-.06917,
.09386,-.06558,
90.*
4,1,17,.06558,.09386,
.048285,.103822,
.029523,.110629,
.009864,.114075,
-.010095,.114055,
-.029747,.110569,
-.048495,.103724,
-.06558,.09386,
-.06917,.09745,
-.051197,.107981,
-.031669,.115231,
-.011178,.118979,
.009652,.119113,
.030189,.115627,
.049809,.108628,
.067916,.098328,
.06917,.09745,
.06558,.09386,
90.*
%
%ADD26MACRO26*%
%ADD16C,.032*%
%ADD15C,.063*%
%ADD12C,.036*%
%ADD13C,.068*%
%ADD22C,.069*%
%AMMACRO24*
4,1,15,.00398,.00044,
.003999,.000208,
.004004,-.000025,
.003996,-.000258,
.00398,-.00044,
.00483,-.00129,
.004897,-.001007,
.004947,-.000721,
.004981,-.000432,
.004997,-.000141,
.004997,.000149,
.00498,.00044,
.004946,.000729,
.004895,.001015,
.00483,.00129,
.00398,.00044,
90.*
4,1,15,.00044,-.00398,
.000208,-.003999,
-.000025,-.004004,
-.000258,-.003996,
-.00044,-.00398,
-.00129,-.00483,
-.001007,-.004897,
-.000721,-.004947,
-.000432,-.004981,
-.000141,-.004997,
.000149,-.004997,
.00044,-.00498,
.000729,-.004946,
.001015,-.004895,
.00129,-.00483,
.00044,-.00398,
90.*
4,1,15,-.00398,-.00044,
-.003999,-.000208,
-.004004,.000025,
-.003996,.000258,
-.00398,.00044,
-.00483,.00129,
-.004897,.001007,
-.004947,.000721,
-.004981,.000432,
-.004997,.000141,
-.004997,-.000149,
-.00498,-.00044,
-.004946,-.000729,
-.004895,-.001015,
-.00483,-.00129,
-.00398,-.00044,
90.*
4,1,15,-.00044,.00398,
-.000208,.003999,
.000025,.004004,
.000258,.003996,
.00044,.00398,
.00129,.00483,
.001007,.004897,
.000721,.004947,
.000432,.004981,
.000141,.004997,
-.000149,.004997,
-.00044,.00498,
-.000729,.004946,
-.001015,.004895,
-.00129,.00483,
-.00044,.00398,
90.*
%
%ADD24MACRO24*%
%AMMACRO17*
4,1,15,.00398,.00044,
.003999,.000208,
.004004,-.000025,
.003996,-.000258,
.00398,-.00044,
.00483,-.00129,
.004897,-.001007,
.004947,-.000721,
.004981,-.000432,
.004997,-.000141,
.004997,.000149,
.00498,.00044,
.004946,.000729,
.004895,.001015,
.00483,.00129,
.00398,.00044,
0.0*
4,1,15,.00044,-.00398,
.000208,-.003999,
-.000025,-.004004,
-.000258,-.003996,
-.00044,-.00398,
-.00129,-.00483,
-.001007,-.004897,
-.000721,-.004947,
-.000432,-.004981,
-.000141,-.004997,
.000149,-.004997,
.00044,-.00498,
.000729,-.004946,
.001015,-.004895,
.00129,-.00483,
.00044,-.00398,
0.0*
4,1,15,-.00398,-.00044,
-.003999,-.000208,
-.004004,.000025,
-.003996,.000258,
-.00398,.00044,
-.00483,.00129,
-.004897,.001007,
-.004947,.000721,
-.004981,.000432,
-.004997,.000141,
-.004997,-.000149,
-.00498,-.00044,
-.004946,-.000729,
-.004895,-.001015,
-.00483,-.00129,
-.00398,-.00044,
0.0*
4,1,15,-.00044,.00398,
-.000208,.003999,
.000025,.004004,
.000258,.003996,
.00044,.00398,
.00129,.00483,
.001007,.004897,
.000721,.004947,
.000432,.004981,
.000141,.004997,
-.000149,.004997,
-.00044,.00498,
-.000729,.004946,
-.001015,.004895,
-.00129,.00483,
-.00044,.00398,
0.0*
%
%ADD17MACRO17*%
%AMMACRO23*
4,1,14,.0267,.01255,
.028474,.007723,
.029382,.002661,
.029398,-.002481,
.02852,-.007549,
.026776,-.012386,
.0267,-.01255,
.03042,-.01628,
.032785,-.01075,
.034154,-.004894,
.034484,.001111,
.033768,.007082,
.032025,.012838,
.03042,.01628,
.0267,.01255,
270.*
4,1,14,.01255,-.0267,
.007723,-.028474,
.002661,-.029382,
-.002481,-.029398,
-.007549,-.02852,
-.012386,-.026776,
-.01255,-.0267,
-.01628,-.03042,
-.01075,-.032785,
-.004894,-.034154,
.001111,-.034484,
.007082,-.033768,
.012838,-.032025,
.01628,-.03042,
.01255,-.0267,
270.*
4,1,14,-.0267,-.01255,
-.028474,-.007723,
-.029382,-.002661,
-.029398,.002481,
-.02852,.007549,
-.026776,.012386,
-.0267,.01255,
-.03042,.01628,
-.032785,.01075,
-.034154,.004894,
-.034484,-.001111,
-.033768,-.007082,
-.032025,-.012838,
-.03042,-.01628,
-.0267,-.01255,
270.*
4,1,14,-.01255,.0267,
-.007723,.028474,
-.002661,.029382,
.002481,.029398,
.007549,.02852,
.012386,.026776,
.01255,.0267,
.01628,.03042,
.01075,.032785,
.004894,.034154,
-.001111,.034484,
-.007082,.033768,
-.012838,.032025,
-.01628,.03042,
-.01255,.0267,
270.*
%
%ADD23MACRO23*%
%ADD19C,.143*%
%ADD11C,.17*%
%ADD21C,.127*%
%ADD20C,.154*%
%ADD27C,.239*%
%ADD10C,.168*%
%ADD18C,.178*%
%ADD14C,.198*%
%AMMACRO25*
4,1,15,.00398,.00044,
.003999,.000208,
.004004,-.000025,
.003996,-.000258,
.00398,-.00044,
.00483,-.00129,
.004897,-.001007,
.004947,-.000721,
.004981,-.000432,
.004997,-.000141,
.004997,.000149,
.00498,.00044,
.004946,.000729,
.004895,.001015,
.00483,.00129,
.00398,.00044,
180.*
4,1,15,.00044,-.00398,
.000208,-.003999,
-.000025,-.004004,
-.000258,-.003996,
-.00044,-.00398,
-.00129,-.00483,
-.001007,-.004897,
-.000721,-.004947,
-.000432,-.004981,
-.000141,-.004997,
.000149,-.004997,
.00044,-.00498,
.000729,-.004946,
.001015,-.004895,
.00129,-.00483,
.00044,-.00398,
180.*
4,1,15,-.00398,-.00044,
-.003999,-.000208,
-.004004,.000025,
-.003996,.000258,
-.00398,.00044,
-.00483,.00129,
-.004897,.001007,
-.004947,.000721,
-.004981,.000432,
-.004997,.000141,
-.004997,-.000149,
-.00498,-.00044,
-.004946,-.000729,
-.004895,-.001015,
-.00483,-.00129,
-.00398,-.00044,
180.*
4,1,15,-.00044,.00398,
-.000208,.003999,
.000025,.004004,
.000258,.003996,
.00044,.00398,
.00129,.00483,
.001007,.004897,
.000721,.004947,
.000432,.004981,
.000141,.004997,
-.000149,.004997,
-.00044,.00498,
-.000729,.004946,
-.001015,.004895,
-.00129,.00483,
-.00044,.00398,
180.*
%
%ADD25MACRO25*%
%ADD28C,.02*%
%ADD29C,.006*%
%ADD33C,.12306*%
%ADD32C,.15006*%
%ADD31C,.13906*%
%ADD30C,.16606*%
G75*
%LPD*%
G75*
G36*
G01X-6000Y-6000D02*
X212693D01*
Y1974504D01*
X-6000D01*
Y-6000D01*
G37*
%LPC*%
G75*
G36*
G01X3937Y3004D02*
G02X3004Y3937I0J933D01*
G01Y1964567D01*
G02X3937Y1965500I933J0D01*
G01X64961D01*
G02X65894Y1964567I0J-933D01*
G01Y1933071D01*
G03X72835Y1926130I6941J0D01*
G01X202756D01*
G02X203689Y1925197I0J-933D01*
G01Y477838D01*
G02X203006Y477555I-400J0D01*
G01X202311Y478250D01*
X129189D01*
X127250Y476311D01*
Y445689D01*
X127939Y445000D01*
X113250Y430311D01*
Y376189D01*
X116250Y373189D01*
Y354311D01*
X113250Y351311D01*
Y313689D01*
X138750Y288189D01*
Y255689D01*
X145189Y249250D01*
X184811D01*
X188750Y253189D01*
Y311811D01*
X178250Y322311D01*
Y444250D01*
X203689D01*
Y43307D01*
G02X202756Y42374I-933J0D01*
G01X72835D01*
G03X65894Y35433I0J-6941D01*
G01Y3937D01*
G02X64961Y3004I-933J0D01*
G01X3937D01*
G37*
G36*
G01X145811Y250750D02*
X140250Y256311D01*
Y288811D01*
X114750Y314311D01*
Y350689D01*
X117750Y353689D01*
Y373811D01*
X114750Y376811D01*
Y429689D01*
X129311Y444250D01*
X159586D01*
X159646Y444182D01*
G03X163554I1954J1718D01*
G01X163614Y444250D01*
X176750D01*
Y321689D01*
X187250Y311189D01*
Y253811D01*
X184189Y250750D01*
X145811D01*
G37*
G36*
G01X129311Y445750D02*
X128750Y446311D01*
Y475689D01*
X129811Y476750D01*
X140503D01*
X140558Y476706D01*
G03X143442I1442J1794D01*
G01X143497Y476750D01*
X201689D01*
X203689Y474750D01*
Y445750D01*
X129311D01*
G37*
%LPD*%
G75*
G36*
G01X188750Y1582689D02*
X184811Y1578750D01*
X50689D01*
X48250Y1581189D01*
Y1581682D01*
X48232Y1581722D01*
G02Y1583878I2368J1078D01*
G01X48250Y1583918D01*
Y1588182D01*
X48232Y1588222D01*
G02Y1590378I2368J1078D01*
G01X48250Y1590418D01*
Y1594182D01*
X48232Y1594222D01*
G02Y1596378I2368J1078D01*
G01X48250Y1596418D01*
Y1600182D01*
X48232Y1600222D01*
G02Y1602378I2368J1078D01*
G01X48250Y1602418D01*
Y1611311D01*
X53189Y1616250D01*
X52250Y1617189D01*
Y1636189D01*
X49750Y1638689D01*
Y1772689D01*
X47750Y1774689D01*
Y1782311D01*
X49750Y1784311D01*
Y1860811D01*
X62189Y1873250D01*
X120311D01*
X130250Y1863311D01*
Y1782602D01*
X130378Y1782553D01*
G02Y1775085I-1441J-3734D01*
G01X130250Y1775036D01*
Y1676311D01*
X137311Y1669250D01*
X184311D01*
X186250Y1667311D01*
Y1617689D01*
X185561Y1617000D01*
X188750Y1613811D01*
Y1582689D01*
G37*
G36*
G01X119250Y255689D02*
X114811Y251250D01*
X77689D01*
X70250Y258689D01*
Y281189D01*
X68189Y283250D01*
X40689D01*
X37250Y286689D01*
Y436311D01*
X45439Y444500D01*
X39250Y450689D01*
Y473811D01*
X44689Y479250D01*
X61192D01*
X61237Y479275D01*
G02X63763I1263J-2275D01*
G01X63808Y479250D01*
X106443D01*
X106501Y479306D01*
G02X109699I1599J-1656D01*
G01X109757Y479250D01*
X121311D01*
X122816Y477745D01*
X122838Y477732D01*
G02X123732Y476838I-1338J-2232D01*
G01X123745Y476816D01*
X125250Y475311D01*
Y450189D01*
X125052Y449991D01*
X125040Y449935D01*
G02X123065Y447960I-2540J565D01*
G01X123009Y447948D01*
X119311Y444250D01*
X91727D01*
X91669Y444189D01*
G02X87931I-1869J1811D01*
G01X87873Y444250D01*
X87250D01*
Y435811D01*
X96250Y426811D01*
Y374189D01*
X93750Y371689D01*
Y353311D01*
X94811Y352250D01*
X96811D01*
X99750Y349311D01*
Y319811D01*
X119250Y300311D01*
Y255689D01*
G37*
G54D33*
X80709Y139409D03*
X149606D03*
Y309409D03*
G54D32*
X80709Y119409D03*
X149606D03*
Y329409D03*
G54D31*
X47244Y68110D03*
Y501338D03*
Y761181D03*
Y1207323D03*
Y1467165D03*
Y1900393D03*
G54D30*
X29921Y24803D03*
Y111417D03*
Y458031D03*
Y544646D03*
Y717874D03*
Y804488D03*
X30000Y1164000D03*
X29921Y1250630D03*
Y1423858D03*
Y1510472D03*
Y1857086D03*
Y1943701D03*
%LPC*%
G75*
G36*
G01X78311Y252750D02*
X71750Y259311D01*
Y281811D01*
X68811Y284750D01*
X41311D01*
X38750Y287311D01*
Y435689D01*
X47311Y444250D01*
X62692D01*
X62737Y444225D01*
G03X65263I1263J2275D01*
G01X65308Y444250D01*
X85750D01*
Y435189D01*
X94750Y426189D01*
Y374811D01*
X92250Y372311D01*
Y352689D01*
X94189Y350750D01*
X96189D01*
X98250Y348689D01*
Y319189D01*
X117750Y299689D01*
Y256311D01*
X114189Y252750D01*
X78311D01*
G37*
G36*
G01X118689Y445750D02*
X46311D01*
X40750Y451311D01*
Y473189D01*
X45311Y477750D01*
X120689D01*
X123750Y474689D01*
Y450811D01*
X118689Y445750D01*
G37*
G36*
G01X54311Y1617250D02*
X53750Y1617811D01*
Y1636811D01*
X51250Y1639311D01*
Y1773311D01*
X49250Y1775311D01*
Y1781689D01*
X51250Y1783689D01*
Y1860189D01*
X62811Y1871750D01*
X119689D01*
X128750Y1862689D01*
Y1782817D01*
G03Y1774821I187J-3998D01*
G01Y1675689D01*
X136689Y1667750D01*
X183689D01*
X184750Y1666689D01*
Y1618311D01*
X183689Y1617250D01*
X84986D01*
X84926Y1617334D01*
G03X81174I-1876J-1334D01*
G01X81114Y1617250D01*
X54311D01*
G37*
G36*
G01X51311Y1580250D02*
X49750Y1581811D01*
Y1610689D01*
X54811Y1615750D01*
X80756D01*
X80786Y1615586D01*
G03X85314I2264J414D01*
G01X85344Y1615750D01*
X184689D01*
X187250Y1613189D01*
Y1583311D01*
X184189Y1580250D01*
X51311D01*
G37*
%LPD*%
G75*
G54D33*
X80709Y309409D03*
G54D32*
Y329409D03*
G54D26*
X96457Y1747835D03*
Y1823031D03*
G54D16*
X26450Y274750D03*
X25500Y321200D03*
X29500Y343500D03*
X23100Y342400D03*
X23400Y353500D03*
X29500Y410500D03*
X14000Y476000D03*
X28800Y533700D03*
X5304Y548800D03*
Y528900D03*
X5094Y574500D03*
X29500Y586500D03*
X23450Y577491D03*
X25148Y570800D03*
X27000Y573800D03*
X4594Y749000D03*
Y714000D03*
X5094Y1354500D03*
X26700Y1529800D03*
X28000Y1596800D03*
X13300Y1644300D03*
Y1689600D03*
X19542Y1710518D03*
X29100Y1721550D03*
X19200Y1707000D03*
X25000Y1763800D03*
X26750Y1791100D03*
X27400Y1899400D03*
X74000Y60500D03*
X79000Y65500D03*
X75000Y67500D03*
X81500Y75500D03*
X63500Y63500D03*
X59600Y125800D03*
X75300Y155300D03*
X49924Y153261D03*
X53000Y171500D03*
X65000Y166300D03*
X60350Y151950D03*
X39300Y181100D03*
X63500Y179300D03*
X53400Y191300D03*
X39300Y175500D03*
X43700Y181200D03*
X43400Y174325D03*
X32425Y177900D03*
X52700Y162300D03*
X64400Y183400D03*
X52500Y175200D03*
X70500Y190200D03*
X54400Y217000D03*
X65200Y207850D03*
X57424Y232974D03*
X42720Y233990D03*
X65000Y241500D03*
Y235400D03*
X54200Y220700D03*
Y207850D03*
X51700Y234800D03*
X41100Y231000D03*
X71400Y208150D03*
X69900Y236600D03*
X77900Y229034D03*
X70600Y217600D03*
X74800Y231800D03*
X69400Y226100D03*
X61300Y229400D03*
X38000Y228500D03*
X75300Y211300D03*
X72100Y221700D03*
X49700Y209700D03*
X53500Y199700D03*
X47800Y199200D03*
X64000Y199700D03*
X60300Y275700D03*
X57500Y268500D03*
X68000Y268000D03*
X70600Y250500D03*
X58936Y256289D03*
X36000Y260386D03*
X42500Y260200D03*
X34200Y284800D03*
X52500Y248500D03*
X32600Y290500D03*
X50800Y266400D03*
X54000Y275600D03*
X45800Y277800D03*
X43400Y272300D03*
X32675Y299500D03*
X78000Y429500D03*
X34000Y448000D03*
X33200Y468900D03*
X51000Y529500D03*
X71445Y532192D03*
X72397Y528297D03*
X77800Y540300D03*
X49700Y568900D03*
X66000Y550500D03*
X65000Y561500D03*
X78400Y583700D03*
X70350Y558850D03*
X54600Y573400D03*
X75571Y692496D03*
X53000Y673500D03*
X57684Y697639D03*
X64000Y666600D03*
X66200Y653500D03*
X82000Y652000D03*
X52500Y682500D03*
X78494Y697835D03*
X53000Y695100D03*
X39800Y681400D03*
X43388Y694286D03*
X44500Y697500D03*
X60900Y670200D03*
X60500Y682540D03*
X76100Y686900D03*
X73000Y728000D03*
X71500Y735500D03*
X73500Y732000D03*
X49500Y703500D03*
X46500Y705500D03*
X57500Y844500D03*
X72400Y822900D03*
X51200Y827000D03*
X61207Y828350D03*
X49600Y889400D03*
X59500Y881600D03*
X57500Y890300D03*
X56000Y885500D03*
X64600Y882700D03*
X61600Y885200D03*
X67200Y888800D03*
X54300Y915500D03*
X54000Y996500D03*
X70800Y990500D03*
X57500Y987800D03*
Y984300D03*
X53800Y1006200D03*
X53500Y1025500D03*
X56000Y1021500D03*
X54500Y1035500D03*
X51000Y1018000D03*
X64500Y1099000D03*
X37500Y1099823D03*
X70500Y1161500D03*
X73163Y1158780D03*
X68800Y1178800D03*
X39400Y1381300D03*
X44500Y1380500D03*
X45500Y1400000D03*
X45000Y1428000D03*
X80000Y1472000D03*
X36400Y1523400D03*
X67700Y1568700D03*
X43500Y1620700D03*
X42700Y1606000D03*
X38400Y1596700D03*
X42500Y1673000D03*
X35500Y1670500D03*
X43600Y1668300D03*
X43300Y1646600D03*
X31400Y1648200D03*
X45500Y1690000D03*
X41500Y1692000D03*
X44500Y1678000D03*
X40300Y1703900D03*
X44100Y1685200D03*
X34000Y1691500D03*
X45300Y1776300D03*
X52500Y1756000D03*
X62000Y1877000D03*
X57900Y1899800D03*
X65300Y1886600D03*
X55900Y1881500D03*
X38700Y1893800D03*
X41500Y1889500D03*
X60300Y1892300D03*
X47000Y1886200D03*
X79900Y1923000D03*
X84500Y56500D03*
X92500Y73000D03*
X88253Y65500D03*
X117600Y234900D03*
X122100Y230100D03*
X85676Y231100D03*
X127200Y246000D03*
X122500Y441000D03*
X108100Y477650D03*
X108900Y541300D03*
X102700Y541000D03*
X87700Y528000D03*
X132500Y539621D03*
X129000Y597000D03*
X124200Y568400D03*
X119800Y568300D03*
X88000Y586500D03*
X101000Y583000D03*
X96000Y588000D03*
X89000Y595000D03*
X87000Y591000D03*
X121000Y581500D03*
X124900Y582000D03*
X91300Y577000D03*
X92200Y553800D03*
X106300Y553200D03*
X116000Y596900D03*
X113655Y599363D03*
X110400Y550800D03*
X128900Y580500D03*
X122300Y575000D03*
X115300Y551800D03*
X131135Y639554D03*
X84200Y643865D03*
X87000Y648000D03*
X130000Y700500D03*
X122500D03*
X114500D03*
X105500Y702500D03*
X93000Y698500D03*
X88500Y700000D03*
X98000Y698500D03*
X86597Y681103D03*
X100200Y663900D03*
X122500Y653650D03*
X117400Y653100D03*
X118127Y663400D03*
X109005Y665890D03*
X114000Y663350D03*
X83850Y678109D03*
X130000Y753000D03*
Y746000D03*
X119500Y746500D03*
Y739500D03*
X113500Y729000D03*
Y736000D03*
Y747000D03*
Y721000D03*
X106000Y709000D03*
X98000Y703000D03*
Y708000D03*
X86500Y723500D03*
X130000Y764000D03*
X119500Y757500D03*
X113500Y756000D03*
X118700Y840700D03*
X98900Y822900D03*
X114900Y824100D03*
X106404Y840700D03*
X100300Y841000D03*
X111500Y851600D03*
X101500Y874200D03*
X102300Y863438D03*
X107164Y862285D03*
X113400Y862200D03*
X125400Y983600D03*
Y992000D03*
X97300Y990800D03*
X83500Y976300D03*
Y972800D03*
X83000Y979800D03*
X94000Y971800D03*
X104000Y1049500D03*
X127200Y1015200D03*
X104000Y1062500D03*
X105000Y1181000D03*
X119500Y1261000D03*
X119000Y1255968D03*
X128700Y1408000D03*
X125000Y1398500D03*
X100860Y1402260D03*
X111000Y1394000D03*
X125100Y1402500D03*
X131174Y1412700D03*
X83200Y1455500D03*
X89000Y1428171D03*
X110000Y1429500D03*
X132000Y1436500D03*
X112750Y1491250D03*
X121000Y1506500D03*
X113000D03*
X117000D03*
X109000D03*
X133000Y1505500D03*
X128999Y1506499D03*
X125000Y1506500D03*
X132300Y1491100D03*
X108500Y1569000D03*
X83000Y1619703D03*
X113200Y1622800D03*
Y1619300D03*
X83050Y1616000D03*
X91100Y1922800D03*
X128900Y1923300D03*
X104600Y1923400D03*
X149500Y52000D03*
X146960Y432400D03*
X142000Y478500D03*
X165300Y481100D03*
X147000Y529900D03*
X162500Y527900D03*
X159850Y541800D03*
X182588Y542288D03*
X133500Y575500D03*
X145800Y594400D03*
X137000Y589900D03*
X133500Y582000D03*
X134600Y586700D03*
X156300Y552100D03*
X142500Y550000D03*
X135000Y561500D03*
X142100Y581400D03*
X160000Y562500D03*
X147900Y588100D03*
X138900Y650100D03*
X174196Y628196D03*
X139200Y653900D03*
X150978Y687775D03*
X142648Y665429D03*
X165433Y692372D03*
X134600Y665600D03*
X161000Y674000D03*
X157500Y664500D03*
X149000Y677000D03*
X155200Y679500D03*
X161500Y691700D03*
X150700D03*
X166000Y751500D03*
X170000Y745500D03*
X161600Y739800D03*
X161500Y747500D03*
X146000Y726000D03*
X165900Y717300D03*
X147000Y703000D03*
X146000Y738000D03*
X175100Y710000D03*
X158600Y752600D03*
X153192Y705890D03*
X146000Y755000D03*
Y765500D03*
Y796500D03*
Y782500D03*
X166000Y760000D03*
X166500Y775500D03*
X161500Y759000D03*
Y768000D03*
Y778000D03*
X146500Y812000D03*
X146000Y824000D03*
X180000Y856000D03*
X162000Y817500D03*
X174000Y834500D03*
X168000Y830000D03*
X180000Y872500D03*
X179500Y884000D03*
X179900Y900900D03*
X157800Y898000D03*
X147500Y900500D03*
X179900Y925700D03*
X179800Y941400D03*
X180000Y912500D03*
X143000Y953032D03*
X146500Y953030D03*
X149772Y954121D03*
X152747Y952474D03*
X163200Y985200D03*
X163100Y978600D03*
X149800Y1008700D03*
X179000Y1005000D03*
X180000Y960400D03*
X180500Y973200D03*
X150500Y976500D03*
X155000Y974500D03*
X155500Y1030000D03*
X153500Y1033500D03*
X151500Y1030500D03*
X163000Y1042500D03*
X159500Y1062000D03*
X135601Y1416200D03*
X146500Y1397100D03*
X155900D03*
X139900Y1415100D03*
X134500Y1420000D03*
X169000Y1426750D03*
X158500Y1466500D03*
X151500Y1438500D03*
X157500Y1454800D03*
X142500Y1420500D03*
X142000Y1494800D03*
X147500Y1498000D03*
X153500Y1496500D03*
X135008Y1508245D03*
X143518Y1567520D03*
X177500Y1569500D03*
X141500Y1621600D03*
X141300Y1625000D03*
X169876Y1626303D03*
X173270Y1626517D03*
X170000Y1920500D03*
X162100Y1912000D03*
X151900Y1891400D03*
X146300Y1913700D03*
X142400Y1923800D03*
X176700Y1923900D03*
X177700Y1912800D03*
X152500Y1883100D03*
X157900Y1923100D03*
X133500Y1906500D03*
X201500Y165000D03*
X191400Y432405D03*
X202210Y638500D03*
X201500Y691500D03*
X202500Y666000D03*
X201500Y726500D03*
X202500Y755500D03*
X201500Y777000D03*
X201389Y797000D03*
X202500Y822000D03*
Y846500D03*
X202000Y859500D03*
Y890000D03*
X202210Y903500D03*
X202000Y875000D03*
X202500Y945500D03*
X202000Y918000D03*
X201500Y931500D03*
X202500Y1006000D03*
Y977500D03*
Y962000D03*
X201500Y991000D03*
X202000Y1037000D03*
Y1052000D03*
X201500Y1019000D03*
X201389Y1067000D03*
X201500Y1082500D03*
X195000Y1112000D03*
X201500Y1147000D03*
X202000Y1212000D03*
X202500Y1179000D03*
X202000Y1246000D03*
X201500Y1310000D03*
X202500Y1280000D03*
X201500Y1359500D03*
X200700Y1348500D03*
X201700Y1388300D03*
X201500Y1413000D03*
X202400Y1444000D03*
X201389Y1425500D03*
X202210Y1462000D03*
X201500Y1569000D03*
X202000Y1537500D03*
X202210Y1554000D03*
X187500Y1559500D03*
X196500Y1606500D03*
X191700Y1652700D03*
X192500Y1648000D03*
X192650Y1641500D03*
X200500Y1876500D03*
X184500Y1920500D03*
X201200Y1890500D03*
X201100Y1908800D03*
G54D12*
X8594Y6500D03*
X20000Y6000D03*
X17000Y36500D03*
X5594Y87000D03*
Y53500D03*
X29500Y53000D03*
X26000Y87000D03*
X30800Y130300D03*
X4594Y120500D03*
X23500Y124000D03*
X15000Y131500D03*
X14500Y100500D03*
Y112500D03*
X4500Y105500D03*
X5000Y137500D03*
X22500Y190000D03*
X29700Y191400D03*
X5594Y153500D03*
X4594Y187500D03*
X16500Y175000D03*
X15500Y143500D03*
X27000Y182000D03*
X14000Y184000D03*
X4500Y170500D03*
X21500Y241500D03*
X4594Y234000D03*
X24000Y212000D03*
X29000Y200500D03*
X13500Y230500D03*
X13000Y212500D03*
X5000Y221000D03*
X12500Y197500D03*
X4500Y202500D03*
X28050Y256950D03*
X5094Y278000D03*
X6094Y257000D03*
X13500Y279000D03*
X13000Y244000D03*
X12500Y266500D03*
X5500Y269500D03*
X5000Y247500D03*
X19721Y267203D03*
X5594Y312000D03*
X5304Y342500D03*
X4900Y328000D03*
X13500Y303500D03*
X13000Y321000D03*
X13500Y295000D03*
X5500Y295500D03*
X6500Y375000D03*
X27000Y371000D03*
X4800Y356200D03*
X23700Y363900D03*
X29500Y364500D03*
X27000Y377500D03*
Y384000D03*
Y389500D03*
X4594Y421000D03*
X5304Y444500D03*
Y440500D03*
X5000Y408500D03*
X5304Y434500D03*
X4594Y396500D03*
X26500Y440000D03*
X26000Y432500D03*
X23800Y410700D03*
X5094Y469500D03*
X5000Y495000D03*
X4700Y458200D03*
X5000Y486500D03*
X5094Y600000D03*
X13510Y597990D03*
X14000Y614000D03*
X4594Y625000D03*
X18000Y608000D03*
X6000Y612000D03*
Y646000D03*
X26000Y656500D03*
X5594Y688500D03*
X5304Y661000D03*
X14000Y659000D03*
X23000Y677500D03*
X8000Y678000D03*
X31000Y700500D03*
X20000Y696000D03*
X6000Y698000D03*
X28000Y706000D03*
X31000Y747000D03*
X22000Y746000D03*
X27000Y750000D03*
X26000Y732000D03*
X18000Y724000D03*
Y732500D03*
Y712000D03*
X6000Y706500D03*
Y722000D03*
Y730500D03*
X5594Y778000D03*
X6500Y799000D03*
X9500Y804000D03*
X24000Y756000D03*
X30000Y782000D03*
X16100Y794600D03*
X5594Y844500D03*
X6094Y819500D03*
X30500D03*
X10000Y811500D03*
X24000Y846000D03*
X24500Y853500D03*
X16000Y828000D03*
Y814000D03*
Y856000D03*
Y842000D03*
X4500Y833500D03*
X26053Y828247D03*
X5094Y897500D03*
X5594Y869000D03*
X16000Y906000D03*
X18000Y884000D03*
Y870000D03*
X4500Y857500D03*
X5000Y883500D03*
X18500Y896500D03*
X23053Y861247D03*
X5304Y926000D03*
X4594Y954000D03*
X18000Y934000D03*
Y920000D03*
X16000Y948000D03*
X4500Y913000D03*
Y941500D03*
X26053Y938247D03*
X5594Y984500D03*
X28000Y992000D03*
X16000Y962000D03*
Y990000D03*
Y976000D03*
Y1000000D03*
X4500Y970000D03*
Y997000D03*
X25053Y971247D03*
X4594Y1041500D03*
Y1013500D03*
X6000Y1058000D03*
X26000Y1010000D03*
X16000Y1014000D03*
Y1046000D03*
Y1032000D03*
X14000Y1060000D03*
X4500Y1029500D03*
X27553Y1029247D03*
X5094Y1074500D03*
X28000Y1072000D03*
X14000Y1074000D03*
Y1100000D03*
Y1086000D03*
X16000Y1110000D03*
X6000Y1096000D03*
X26100Y1088600D03*
X27218Y1097000D03*
X16000Y1124000D03*
Y1148000D03*
Y1134000D03*
Y1162000D03*
X6000Y1138000D03*
Y1118000D03*
Y1152000D03*
X26600Y1132400D03*
X24553Y1153247D03*
X5304Y1208000D03*
X4594Y1169500D03*
X24000Y1180000D03*
X16000Y1176000D03*
X8500Y1237000D03*
X30000Y1240000D03*
X16000Y1262000D03*
Y1244000D03*
X6000Y1252000D03*
X22000Y1232000D03*
X6500Y1302000D03*
X5094Y1268500D03*
X17700Y1283000D03*
X12000Y1274000D03*
Y1294000D03*
X28000Y1266000D03*
Y1286000D03*
Y1300000D03*
X19800Y1315400D03*
X13500Y1365000D03*
X6000Y1318000D03*
X28000Y1320000D03*
X30800Y1403900D03*
X5304Y1409400D03*
X4594Y1382000D03*
X7500Y1376500D03*
X8000Y1368000D03*
X4800Y1460700D03*
X4594Y1435500D03*
X5304Y1504100D03*
X4600Y1484800D03*
X29500Y1495800D03*
X5304Y1540500D03*
Y1522100D03*
X26600Y1570100D03*
X26900Y1547900D03*
Y1559100D03*
X4594Y1607500D03*
X5304Y1576200D03*
X26700Y1579800D03*
X7500Y1640200D03*
X5304Y1659000D03*
X4594Y1632000D03*
X29000Y1671000D03*
X19250Y1663100D03*
X5304Y1723500D03*
X4900Y1708000D03*
X4594Y1691000D03*
X4700Y1676100D03*
X30000Y1731000D03*
X4594Y1775000D03*
Y1751000D03*
X12600Y1753800D03*
X13100Y1742600D03*
Y1728900D03*
X12900Y1765200D03*
X4594Y1826500D03*
X5900Y1814100D03*
X4594Y1799500D03*
X12600Y1792800D03*
X12500Y1782500D03*
X4594Y1878500D03*
X12800Y1863700D03*
X5000Y1864100D03*
X18600Y1871400D03*
X4594Y1850000D03*
X24200Y1836700D03*
X15000Y1854900D03*
X14500Y1842000D03*
X27500Y1874500D03*
X24800Y1926500D03*
X5094Y1921000D03*
X4594Y1902000D03*
X24500Y1884000D03*
X13100Y1933900D03*
X16100Y1950700D03*
X5094Y1944500D03*
X15500Y1942500D03*
X4500Y1936000D03*
X6500Y1962000D03*
X25000Y1962500D03*
X12500Y1959000D03*
X63594Y7000D03*
Y25500D03*
X40594Y6000D03*
X49000Y18500D03*
X43000Y27000D03*
X64000Y17000D03*
X53000Y5000D03*
X31500Y5500D03*
X51500Y53000D03*
X74000Y45000D03*
X64500Y40000D03*
X32000D03*
X63098Y119103D03*
X52000Y115600D03*
X51700Y131700D03*
X34400Y95300D03*
X71000Y131859D03*
X37000Y124000D03*
X62598Y141103D03*
X51900Y145700D03*
X69000Y153000D03*
X73500Y146000D03*
X60800Y147700D03*
X78200Y481700D03*
X74942Y530983D03*
X72500Y595900D03*
X56800Y576950D03*
X34100Y566600D03*
X36000Y554000D03*
X79122Y565700D03*
X79458Y578758D03*
X69800Y574200D03*
X80900Y668400D03*
X56710Y681069D03*
X69100Y698006D03*
X71800Y701300D03*
X74100Y669398D03*
X32000Y666000D03*
X50000Y712500D03*
Y749000D03*
X40000Y746500D03*
X36000Y730000D03*
X46000Y726000D03*
X44000Y782000D03*
X42000Y802000D03*
Y788000D03*
X47600Y796800D03*
X81500Y837500D03*
X82000Y806500D03*
X48000Y816000D03*
X38000Y834000D03*
Y820000D03*
X46000Y848000D03*
Y834000D03*
X32000Y844000D03*
X78300Y832600D03*
X77600Y849100D03*
X48100Y853400D03*
X45600Y827500D03*
X37500Y907500D03*
X77000Y871500D03*
X79000Y857000D03*
X62500Y862000D03*
X61500Y876500D03*
X78000Y878500D03*
X32000Y858000D03*
Y886000D03*
Y872000D03*
X77500Y907000D03*
X78300Y893900D03*
X77000Y863000D03*
X47000Y877600D03*
X40900Y901500D03*
X41000Y931899D03*
X37500Y912000D03*
X34000Y944000D03*
Y934500D03*
X33500Y953000D03*
X61500Y938500D03*
X81500Y940000D03*
X75500Y936500D03*
X69500Y939000D03*
X55500Y955500D03*
X56500Y940000D03*
X62500Y924500D03*
X70000Y914500D03*
Y925500D03*
X76500Y927000D03*
X77500Y917000D03*
X33500Y962500D03*
X34000Y984000D03*
Y974500D03*
Y1008000D03*
X55500Y968000D03*
X76400Y999100D03*
X37700Y991600D03*
X33600Y1029900D03*
X34000Y1017500D03*
X39300Y1105800D03*
X34000Y1102000D03*
Y1072000D03*
X33550Y1080100D03*
X67302Y1133490D03*
X78292Y1148041D03*
X66000Y1149500D03*
X79044Y1144112D03*
X37500Y1118900D03*
X74000Y1132000D03*
X34000Y1144000D03*
X40000Y1136000D03*
Y1156000D03*
X32000Y1114000D03*
X77293Y1129729D03*
X64500Y1165700D03*
X58000Y1206000D03*
X60000Y1194000D03*
X61000Y1173000D03*
X54000Y1184000D03*
X44000Y1194000D03*
X42000Y1242000D03*
X50000Y1244000D03*
X58000Y1250000D03*
X46000Y1218000D03*
X31500Y1222000D03*
X58000D03*
X39500Y1231000D03*
X51800Y1231600D03*
X50100Y1261500D03*
X42000Y1266000D03*
Y1290000D03*
X34000Y1312000D03*
X40000Y1278000D03*
Y1298000D03*
X44000Y1306000D03*
X58000Y1312000D03*
Y1292000D03*
Y1272000D03*
X52000Y1296300D03*
X61000Y1363500D03*
X38000Y1334000D03*
X50000Y1318000D03*
X44000Y1326000D03*
Y1340000D03*
X54000Y1330000D03*
X72000Y1360000D03*
X31500Y1397500D03*
X81500Y1382000D03*
Y1416500D03*
Y1404000D03*
X52500Y1368500D03*
X71800Y1373900D03*
X70500Y1378500D03*
X69400Y1402900D03*
X39500Y1407900D03*
X55600Y1381700D03*
X48900Y1390500D03*
X60900D03*
X56700Y1400100D03*
X68800Y1417800D03*
X58800Y1412400D03*
X49000Y1413300D03*
X72900Y1393600D03*
X74900Y1408800D03*
X32000Y1391500D03*
X61500Y1380000D03*
X70400Y1444500D03*
X79000Y1436400D03*
X76200Y1430700D03*
X60600Y1423600D03*
X75600Y1420300D03*
X66500Y1433500D03*
X53100Y1430700D03*
X42600Y1444200D03*
X34000Y1465900D03*
X49100Y1448400D03*
X68500Y1454600D03*
X74500Y1461800D03*
X72300Y1469800D03*
X59000Y1444500D03*
X77000Y1449000D03*
X58100Y1459300D03*
X63000Y1482300D03*
X42700Y1500000D03*
X72700Y1480500D03*
X46500Y1484900D03*
X64100Y1495400D03*
X73000Y1491200D03*
X43300Y1518500D03*
X49500Y1505000D03*
X59000Y1472000D03*
X34000Y1477600D03*
X46600Y1541100D03*
X45300Y1563600D03*
X45900Y1532800D03*
X45400Y1523800D03*
X37900Y1570000D03*
X38800Y1541700D03*
X38300Y1561800D03*
X44400Y1592100D03*
X33100Y1587400D03*
X38300Y1579600D03*
X43200Y1634800D03*
X42500Y1699500D03*
X44600Y1724400D03*
X44900Y1706800D03*
X53000Y1750500D03*
X36700Y1764700D03*
X56500Y1769300D03*
X44900Y1740300D03*
X44400Y1821400D03*
X39179Y1792306D03*
X39700Y1869700D03*
X46700Y1857700D03*
X46500Y1850200D03*
X44500Y1833500D03*
X39700Y1846600D03*
X45500Y1865000D03*
X31500Y1878500D03*
X36000Y1835500D03*
X54500Y1889500D03*
X63500Y1928000D03*
X61500Y1922500D03*
X46000Y1923000D03*
X54000Y1928500D03*
X35300Y1925300D03*
X36500Y1900500D03*
X63500Y1963000D03*
X63594Y1935500D03*
X61600Y1954700D03*
X34500Y1963200D03*
X41100Y1957500D03*
X55300Y1959100D03*
X45100Y1933400D03*
X35000Y1933500D03*
X43500Y1945000D03*
X49053Y1951747D03*
X128500Y89000D03*
X118000Y54500D03*
X124000Y74500D03*
X105000Y55000D03*
X85000Y45000D03*
X105000D03*
X95000D03*
X115000D03*
X125000D03*
X127700Y119200D03*
X128700Y104200D03*
X131000Y138100D03*
X118000Y124500D03*
X119000Y109500D03*
X95000Y125000D03*
X105000D03*
X95000Y134000D03*
X86000Y152000D03*
X129000Y160100D03*
X131000Y150100D03*
X118000Y154500D03*
Y142500D03*
X95000Y143000D03*
X105000D03*
X95000Y155000D03*
X105000D03*
X131800Y289700D03*
X130900Y259100D03*
X111500Y390000D03*
X101300Y390100D03*
X105500Y390000D03*
Y406500D03*
X101500D03*
X107000Y426500D03*
X98000D03*
X102500D03*
X111200Y426400D03*
X110500Y406500D03*
X117000Y530000D03*
X103100Y587600D03*
X87595Y581300D03*
X90630Y602020D03*
X86443Y662853D03*
X88967Y659749D03*
X84504Y666353D03*
X90674Y663367D03*
X121500Y683500D03*
X119576Y687008D03*
X120702Y690847D03*
X100600Y670600D03*
X112800Y653500D03*
X108200Y655825D03*
X119000Y673300D03*
X87310Y676796D03*
X124800Y696600D03*
X129800Y696800D03*
X98000Y674327D03*
X102913Y673973D03*
X107113Y674001D03*
X108500Y695500D03*
X103500D03*
X99001Y694866D03*
X125000Y734000D03*
X116500Y752000D03*
X125000Y751000D03*
X125500Y741500D03*
X130000Y736500D03*
X120500Y732500D03*
X120000Y717500D03*
X115000Y704500D03*
X123000Y800000D03*
X122500Y792500D03*
X114000Y800000D03*
X113500Y792500D03*
X130000Y800000D03*
X129500Y792500D03*
X121500Y783500D03*
X121000Y776000D03*
X129500Y782000D03*
X129000Y774500D03*
X125000Y758500D03*
X115200Y784200D03*
X115000Y773200D03*
X121000Y767900D03*
X95500Y841500D03*
X82500Y814000D03*
X123500Y842500D03*
Y816000D03*
X123000Y808500D03*
X115000Y813000D03*
X114500Y805500D03*
X129200Y830400D03*
X129800Y813500D03*
X124500Y825100D03*
X90500Y831500D03*
X87000Y839500D03*
X85500Y903000D03*
X116053Y903247D03*
X127000Y903000D03*
X90000Y893000D03*
X102500Y893500D03*
X117500Y893000D03*
X125000Y868500D03*
X124500Y858000D03*
X107000Y903000D03*
X124500Y876500D03*
X126000Y892500D03*
X96053Y903247D03*
X83400Y878600D03*
X125500Y944000D03*
X105000Y958000D03*
X86500Y932000D03*
X96500Y916500D03*
X107000Y918000D03*
X115000Y920000D03*
X125500D03*
X126000Y930000D03*
X115500D03*
X99000Y953000D03*
X88500Y940500D03*
X120000Y916000D03*
X124000Y909000D03*
X113500Y909500D03*
X103500D03*
X94000Y910500D03*
X85500Y915000D03*
X126000Y954000D03*
X110000Y949500D03*
X117529Y948844D03*
X93000Y925500D03*
X125000Y967000D03*
X130500Y966000D03*
X124000Y971500D03*
X117000Y1008500D03*
X105500Y996000D03*
X95500Y999000D03*
X87000Y997500D03*
X106500Y1008500D03*
X119000Y975000D03*
X108500Y964000D03*
Y971000D03*
X114800Y1005000D03*
X124618Y959244D03*
X110500Y1041500D03*
X111500Y1030000D03*
Y1020000D03*
X104000Y1014000D03*
X110500Y1051000D03*
X103500Y1042000D03*
Y1028500D03*
X116500Y1049000D03*
Y1035500D03*
X117500Y1023500D03*
X120000Y1108000D03*
Y1102000D03*
X115000Y1108500D03*
X110500Y1064500D03*
Y1112000D03*
X103500Y1073500D03*
X104500Y1095000D03*
X116500Y1076000D03*
X109000Y1083500D03*
X116500Y1062500D03*
X89000Y1167400D03*
X118500Y1166000D03*
X105000Y1196000D03*
X119300Y1191400D03*
X119500Y1177500D03*
Y1205500D03*
X104500Y1208000D03*
X94000Y1189000D03*
X91500Y1200000D03*
X99000Y1265500D03*
X117500Y1251000D03*
X112000Y1250500D03*
Y1244500D03*
X119300Y1245400D03*
Y1219400D03*
X119500Y1231500D03*
X104500Y1219500D03*
X92000Y1254000D03*
X103500Y1229000D03*
X92000Y1241500D03*
X103000Y1244900D03*
X92000Y1214500D03*
X91500Y1229000D03*
X119000Y1269000D03*
X99500Y1310000D03*
Y1294000D03*
X98000Y1282000D03*
X123800Y1283900D03*
X124000Y1270000D03*
X113800Y1287900D03*
X114000Y1274000D03*
X123800Y1311900D03*
X124000Y1298000D03*
X92000Y1295500D03*
X91500Y1314500D03*
X114500Y1296500D03*
X97800Y1327900D03*
X123800Y1337900D03*
X124000Y1324000D03*
X113800Y1331900D03*
X114000Y1318000D03*
X115800Y1363900D03*
X116000Y1350000D03*
X123800Y1365900D03*
X124000Y1352000D03*
X83800Y1365900D03*
X84000Y1352000D03*
X93800Y1353900D03*
X94000Y1340000D03*
Y1366000D03*
X90800Y1331200D03*
X105500Y1415000D03*
X99600Y1416500D03*
X100500Y1384500D03*
Y1389000D03*
X124000Y1376500D03*
X114000Y1376000D03*
X114500Y1370500D03*
X83800Y1391900D03*
X93800Y1379900D03*
Y1393200D03*
X93600Y1407100D03*
X97500Y1412000D03*
X89700Y1409700D03*
X110000Y1418000D03*
X86900Y1451000D03*
X126600Y1461500D03*
X132200Y1424800D03*
X94000Y1427800D03*
X87200Y1431900D03*
X87700Y1446500D03*
X87300Y1436000D03*
X95500Y1468000D03*
X113024Y1452079D03*
X117122Y1448001D03*
X117195Y1456070D03*
X121338Y1452021D03*
X117024Y1452000D03*
X83500Y1469500D03*
X87200Y1440000D03*
X99800Y1455600D03*
X109500Y1438000D03*
X98500Y1428400D03*
X117000Y1435200D03*
X91300Y1488600D03*
X97000Y1503100D03*
X93500Y1482700D03*
X99170Y1485790D03*
X103700Y1470300D03*
X85000Y1490000D03*
X118000Y1922000D03*
X184000Y55500D03*
X174000D03*
X164000D03*
X154000Y75500D03*
X135000Y50000D03*
Y70000D03*
Y45000D03*
X145000D03*
X155000D03*
X165000D03*
X175000D03*
X137200Y123600D03*
X180500Y112000D03*
X167000Y130500D03*
X176000Y131000D03*
X167000Y93000D03*
X153000Y90500D03*
X171500Y105500D03*
X170500Y120500D03*
X146500Y131859D03*
X154000Y105500D03*
X147600Y150900D03*
X165300Y145200D03*
X137900Y171400D03*
X174500Y143500D03*
X173500Y151500D03*
X138800Y162100D03*
X141300Y298100D03*
X181800Y369000D03*
X181100Y364050D03*
X180850Y348800D03*
X144600Y533800D03*
X182600Y546900D03*
X180500Y595000D03*
X171600Y595400D03*
X147500Y551500D03*
X141800Y559250D03*
X150500Y596000D03*
X153500Y574359D03*
X140700Y576600D03*
X152700Y618803D03*
X170349Y619949D03*
X145500Y604000D03*
X175800Y617635D03*
X164950Y615700D03*
X180500Y627771D03*
X165600Y630269D03*
X151432Y661741D03*
X148995Y658568D03*
X134100Y674500D03*
X176000Y679000D03*
Y665500D03*
X167300Y653800D03*
X162300Y659100D03*
X183500Y698000D03*
X165500Y677500D03*
X159700Y652000D03*
X181000Y729000D03*
Y715500D03*
X182500Y745000D03*
X181500Y738500D03*
X169100Y722100D03*
X169000Y795500D03*
X178000Y797500D03*
X175000Y786500D03*
X182500Y758500D03*
X173500Y777500D03*
Y764000D03*
X172000Y757500D03*
X181700Y768400D03*
X165000Y786000D03*
X171500Y819500D03*
X163500Y805500D03*
X177500Y812000D03*
Y826500D03*
X140500Y846500D03*
X134500Y840500D03*
X145500Y885000D03*
X137500Y903000D03*
X146000Y893000D03*
X135000D03*
X134500Y885500D03*
X137500Y876500D03*
X145500Y856500D03*
X157500Y858000D03*
X156300Y877200D03*
X156500Y889000D03*
X153500Y941000D03*
X141000Y938500D03*
X135000Y918000D03*
X135500Y927500D03*
X144000Y919500D03*
Y929000D03*
X143000Y910500D03*
X135500Y909000D03*
X154700Y909700D03*
X154500Y926500D03*
X182000Y950500D03*
X133500Y938000D03*
X134000Y990500D03*
X136500Y967000D03*
X184000Y987500D03*
X135000Y975500D03*
X146800Y1018900D03*
X143900Y1022700D03*
X174000Y1012400D03*
X166300Y1021300D03*
X182500Y1041500D03*
X182000Y1029500D03*
Y1016000D03*
X171000Y1046000D03*
Y1032500D03*
X175000Y1059000D03*
X160500Y1053500D03*
X181000Y1051000D03*
X164700Y1033600D03*
X176000Y1018500D03*
X183500Y1065500D03*
X171000Y1068000D03*
X166000Y1080000D03*
X173000Y1082000D03*
X165000Y1097000D03*
X181000Y1098500D03*
X175000Y1072500D03*
X160500Y1067000D03*
X170000Y1103000D03*
Y1089500D03*
X157000Y1101500D03*
X159500Y1087500D03*
X181000Y1079500D03*
X154600Y1111000D03*
X158500Y1075800D03*
X158595Y1110789D03*
X181000Y1112500D03*
X177102Y1129800D03*
X171502Y1129547D03*
X147500Y1165500D03*
Y1186000D03*
X178644Y1202519D03*
X163344Y1181200D03*
X147500Y1221500D03*
X146500Y1241500D03*
X147000Y1265500D03*
X183500Y1241500D03*
X165000Y1264500D03*
X147500Y1288000D03*
Y1311000D03*
X164500Y1299500D03*
X147500Y1332000D03*
X147000Y1348000D03*
X147500Y1366500D03*
X147000Y1377000D03*
X146500Y1417619D03*
X137000Y1429200D03*
X173375Y1432500D03*
X149686Y1460007D03*
X133500Y1467100D03*
X152500Y1456000D03*
X133799Y1440699D03*
X141500Y1673000D03*
X139000Y1696500D03*
Y1712500D03*
X181500Y1716500D03*
X158500D03*
X167500Y1716000D03*
X182000Y1704000D03*
X168500Y1705000D03*
X158500D03*
X163000Y1697000D03*
X174268Y1697110D03*
X152000D03*
Y1710610D03*
Y1725610D03*
X138500Y1727500D03*
X182000Y1726000D03*
X183600Y1765100D03*
X162500Y1773000D03*
X152500Y1771110D03*
X173268Y1776000D03*
X139000Y1800500D03*
X138000Y1824000D03*
X169000Y1781500D03*
X156500Y1782000D03*
X155500Y1798500D03*
X166500Y1798000D03*
X179000Y1798500D03*
X162000Y1790000D03*
X172768Y1790110D03*
X152000D03*
X139000Y1851000D03*
X138500Y1839500D03*
X161500Y1852500D03*
X183100Y1838300D03*
X160500Y1877500D03*
X173000Y1852610D03*
X151500Y1851110D03*
X161000Y1901500D03*
X194000Y55500D03*
X185000Y45000D03*
X195000D03*
X200000Y55000D03*
Y65000D03*
Y75000D03*
Y85000D03*
X187500Y130500D03*
X190500Y105000D03*
X189500Y120000D03*
X200000Y100000D03*
Y120000D03*
Y140000D03*
X191900Y167700D03*
X191700Y186500D03*
X186000Y143000D03*
X201089Y181700D03*
X197500Y151500D03*
X185500D03*
X191800Y234900D03*
Y221100D03*
X191600Y206900D03*
X201500Y208000D03*
X201000Y222500D03*
X200500Y235000D03*
Y195900D03*
X191900Y244600D03*
X202000Y274000D03*
Y254000D03*
X201089Y282600D03*
X202000Y264000D03*
X187500Y338000D03*
X202000Y340000D03*
Y328000D03*
Y295000D03*
X201089Y305500D03*
Y315500D03*
X184500Y325500D03*
X201500Y378000D03*
X202000Y366500D03*
Y353000D03*
X188500Y364100D03*
X188300Y368600D03*
X192600Y392600D03*
X201089Y388400D03*
X201500Y397500D03*
X200500Y437500D03*
X201000Y430500D03*
X201089Y407000D03*
X200000Y420500D03*
X192471Y397355D03*
X192400Y401900D03*
X186600Y425750D03*
X192300Y410950D03*
X192409Y417655D03*
X201500Y544500D03*
X201089Y529500D03*
X192400Y529400D03*
X191900Y538200D03*
X201500Y535000D03*
X192000Y543500D03*
X202000Y578000D03*
Y586000D03*
Y595000D03*
X193700D03*
X194400Y586000D03*
X201500Y552500D03*
X201089Y558000D03*
X201500Y564000D03*
X201089Y570600D03*
X190500Y550500D03*
X202000Y607500D03*
X196500Y641500D03*
X192600Y633000D03*
X201500Y621500D03*
X202000Y650500D03*
X194000Y628500D03*
Y615000D03*
X192500Y645000D03*
X195000Y670000D03*
X185000Y673500D03*
X188100Y689100D03*
X197500Y685000D03*
X202000Y676500D03*
X192500Y658500D03*
X191500Y692500D03*
X193100Y679000D03*
X184700Y663900D03*
X196000Y718500D03*
X184500Y708500D03*
X197000Y704000D03*
X195500Y739000D03*
X197500Y753000D03*
X202000Y710000D03*
Y740500D03*
X191500Y724000D03*
Y710500D03*
Y746500D03*
X196000Y789500D03*
X196500Y797000D03*
X187900Y785300D03*
X202000Y765000D03*
Y786000D03*
X191500Y760000D03*
X194500Y782500D03*
Y769000D03*
X196800Y828500D03*
X197000Y815000D03*
X190000Y823500D03*
X190500Y831000D03*
X202000Y807500D03*
X201500Y835500D03*
X192500Y853000D03*
Y839500D03*
X185000Y843500D03*
X184500Y879000D03*
Y865500D03*
X192000Y879000D03*
Y865500D03*
X194000Y907000D03*
Y893500D03*
X187000Y891000D03*
X192000Y934500D03*
Y921000D03*
Y948500D03*
X185000Y917500D03*
X192000Y962000D03*
X192500Y985500D03*
Y972000D03*
X195500Y1001000D03*
X190000Y1052000D03*
X195500Y1014500D03*
X193500Y1042500D03*
Y1029000D03*
X195000Y1086500D03*
X194500Y1100500D03*
X195000Y1074500D03*
Y1061000D03*
X201000Y1106500D03*
Y1093000D03*
X187500Y1103500D03*
Y1090000D03*
X191800Y1280900D03*
X194500Y1546000D03*
X193000Y1556500D03*
X197000Y1551500D03*
X195500Y1530500D03*
X193000Y1562500D03*
X189400Y1544100D03*
X187900Y1566600D03*
X189500Y1577000D03*
X198500Y1584000D03*
X192000Y1586000D03*
X197500Y1593000D03*
X191500Y1595000D03*
X199000Y1619500D03*
X190000Y1622000D03*
X198000Y1632500D03*
X191500Y1631000D03*
X198000Y1647500D03*
X196500Y1656000D03*
X197000Y1713000D03*
Y1691500D03*
X184500Y1696500D03*
X197500Y1776500D03*
Y1754000D03*
X197000Y1735500D03*
X185000Y1738500D03*
X198000Y1818500D03*
X196500Y1800500D03*
X185500Y1804500D03*
X186000Y1790000D03*
X197500Y1860000D03*
X197000Y1838500D03*
X194400Y1876700D03*
X185000Y1852500D03*
X201500Y1900500D03*
X190500Y1924000D03*
X201000Y1923000D03*
X195500Y1905000D03*
X196500Y1882000D03*
G54D15*
X31299Y230866D03*
Y220866D03*
Y210866D03*
Y338563D03*
Y358563D03*
Y348563D03*
Y903917D03*
Y923917D03*
Y913917D03*
Y1054587D03*
Y1044587D03*
Y1064587D03*
Y1619941D03*
Y1609941D03*
Y1629941D03*
Y1757638D03*
Y1747638D03*
Y1737638D03*
G54D13*
X15906Y48110D03*
Y58110D03*
Y68110D03*
Y78110D03*
Y88110D03*
Y481339D03*
Y491339D03*
Y501339D03*
Y511339D03*
Y521339D03*
Y741181D03*
Y751181D03*
Y761181D03*
Y771181D03*
Y781181D03*
Y1187323D03*
Y1197323D03*
Y1207323D03*
Y1217323D03*
Y1227323D03*
Y1447165D03*
Y1457165D03*
Y1467165D03*
Y1477165D03*
Y1487165D03*
Y1880394D03*
Y1890394D03*
Y1900394D03*
Y1910394D03*
Y1920394D03*
X128937Y1778819D03*
X118937D03*
X165000Y1390500D03*
Y1380500D03*
Y1370500D03*
X138937Y1778819D03*
G54D22*
X80709Y161889D03*
Y171889D03*
Y181889D03*
Y191889D03*
Y204409D03*
Y214409D03*
Y224409D03*
Y234409D03*
Y244409D03*
X110709Y161889D03*
Y171889D03*
X100709Y161889D03*
Y171889D03*
X90709Y161889D03*
Y171889D03*
X110709Y181889D03*
Y191889D03*
X100709Y181889D03*
Y191889D03*
X90709Y181889D03*
Y191889D03*
X110709Y204409D03*
Y214409D03*
Y224409D03*
Y234409D03*
Y244409D03*
X100709Y204409D03*
Y214409D03*
Y224409D03*
Y234409D03*
Y244409D03*
X90709Y204409D03*
Y214409D03*
Y224409D03*
Y234409D03*
Y244409D03*
X179606Y161889D03*
Y171889D03*
X169606Y161889D03*
Y171889D03*
X159606Y161889D03*
Y171889D03*
X149606Y161889D03*
Y171889D03*
X179606Y181889D03*
Y191889D03*
X169606Y181889D03*
Y191889D03*
X159606Y181889D03*
Y191889D03*
X149606Y181889D03*
Y191889D03*
X179606Y204409D03*
Y214409D03*
Y224409D03*
Y234409D03*
Y244409D03*
X169606Y204409D03*
Y214409D03*
Y224409D03*
Y234409D03*
Y244409D03*
X159606Y204409D03*
Y214409D03*
Y224409D03*
Y234409D03*
Y244409D03*
X149606Y204409D03*
Y214409D03*
Y224409D03*
Y234409D03*
Y244409D03*
G54D24*
X68000Y286000D03*
Y320000D03*
Y312000D03*
X76000Y296000D03*
X68000Y304000D03*
X74000Y390000D03*
X66000D03*
X58000D03*
X74000Y408000D03*
X66000D03*
Y418000D03*
X74000D03*
X73700Y423000D03*
X66000Y426000D03*
X74000Y400000D03*
X66000D03*
X58000D03*
Y417500D03*
X71600Y1607700D03*
X58500D03*
X102000Y312000D03*
X104000Y304000D03*
X94000D03*
Y312000D03*
Y320000D03*
X118000Y396000D03*
Y386000D03*
Y414000D03*
X106882Y794201D03*
X107000Y798200D03*
Y802400D03*
X104000Y1605500D03*
X94500D03*
X142000Y291000D03*
X143400Y318700D03*
X174000Y316000D03*
X164000D03*
X182000Y296000D03*
X172000D03*
X162000D03*
X172000Y310000D03*
X182000D03*
X184000Y303000D03*
X176000Y302000D03*
X166000D03*
X143300Y343400D03*
X151300Y298200D03*
X150000Y386000D03*
X134000Y396000D03*
X150000D03*
X134000Y386000D03*
Y404500D03*
Y414000D03*
X150000Y404000D03*
Y414000D03*
X134000Y424000D03*
X150000D03*
X182500Y1599400D03*
X146000Y1612000D03*
X148000Y1606000D03*
X182500Y1592000D03*
X138500Y1606000D03*
X182500Y1584500D03*
G54D17*
X21600Y333800D03*
X10500Y1648800D03*
X13900Y1706200D03*
X70454Y60031D03*
X64500Y53000D03*
X64000Y67553D03*
X48500Y248600D03*
X42500Y254100D03*
X68000Y296000D03*
X64000Y446500D03*
X58100Y431900D03*
X63096Y434540D03*
X68500Y434300D03*
X82000Y483600D03*
X46000Y490500D03*
X50100Y493000D03*
X42500D03*
X63300Y464400D03*
X64000Y451000D03*
Y455500D03*
Y460000D03*
X62500Y472900D03*
X62600Y468500D03*
X62500Y477000D03*
X52100Y513100D03*
X46500Y511000D03*
X46000Y516000D03*
X78500Y506700D03*
X78200Y501000D03*
X71800Y506900D03*
X71900Y501000D03*
X72100Y521800D03*
X79400D03*
X72000Y514800D03*
X78000D03*
X51700Y522500D03*
X33450Y574300D03*
X63400Y581400D03*
X40000Y659000D03*
X43281Y674991D03*
X39096Y674917D03*
X69000Y726800D03*
X55700Y880000D03*
X64000Y980500D03*
X31600Y1024300D03*
X71100Y1171000D03*
X53500Y1519000D03*
X72000Y1514000D03*
X58500Y1519000D03*
X57000Y1568500D03*
X57500Y1562000D03*
X59500Y1541000D03*
X54300Y1541200D03*
X80000Y1531600D03*
X73900Y1535900D03*
X54500Y1574000D03*
X50600Y1589300D03*
Y1582800D03*
Y1595300D03*
Y1601300D03*
X55300Y1601100D03*
Y1595100D03*
Y1582600D03*
Y1589100D03*
X68700Y1603900D03*
X55400Y1613300D03*
X59500Y1667000D03*
X70000Y1668000D03*
X76000Y1646000D03*
Y1634000D03*
X75500Y1659500D03*
X54000Y1646500D03*
X64500Y1646000D03*
X55000Y1634000D03*
X64000D03*
X64500Y1658500D03*
X53500Y1659000D03*
X56000Y1695000D03*
Y1704500D03*
Y1712500D03*
X55500Y1723500D03*
X69000Y1684500D03*
X80500D03*
X62500Y1691500D03*
X65000Y1724000D03*
X62500Y1709000D03*
X72500Y1717000D03*
Y1699000D03*
X75500Y1679000D03*
X62500Y1700000D03*
X38800Y1775000D03*
X41600Y1746900D03*
X48400D03*
X64500Y1758500D03*
X55500Y1735500D03*
X65000Y1735000D03*
X79000Y1766500D03*
X65000Y1749000D03*
Y1768000D03*
Y1742500D03*
X71500Y1760000D03*
X72500Y1733000D03*
X60000Y1730000D03*
X42000Y1784400D03*
X81000Y1802000D03*
X73000Y1813000D03*
X64500Y1821500D03*
Y1812000D03*
Y1801500D03*
X65000Y1790000D03*
X72000Y1798000D03*
X75500Y1838500D03*
X63500Y1863000D03*
Y1856000D03*
X64000Y1844500D03*
Y1834000D03*
X73000Y1847000D03*
X72500Y1830000D03*
X91500Y88500D03*
X97000Y51500D03*
X115500Y59500D03*
X98500Y73000D03*
X109000Y76500D03*
X115000D03*
X99500Y61000D03*
X89500Y49500D03*
X109500Y62000D03*
X93500Y101500D03*
X93900Y111800D03*
X93000Y107000D03*
X91000Y97000D03*
X91500Y92500D03*
X104500Y101000D03*
X112000D03*
X114000Y296000D03*
X106000D03*
X96000D03*
X86000D03*
X89800Y446000D03*
X131000Y447000D03*
X84500Y433000D03*
X88500Y426500D03*
X130000Y432000D03*
X129000Y485500D03*
X120000D03*
X110800Y482600D03*
X99800Y482000D03*
X110800Y488600D03*
X100000Y488000D03*
Y494000D03*
X110800Y494600D03*
X129000Y493500D03*
X120000D03*
X122500Y450500D03*
Y457500D03*
Y463500D03*
X121500Y475500D03*
X122500Y469500D03*
X117000Y455000D03*
Y460500D03*
Y466000D03*
Y471500D03*
Y449000D03*
X89800Y452900D03*
Y459000D03*
X111500Y473000D03*
X99500D03*
X89800Y464800D03*
X130500Y454000D03*
Y461000D03*
Y468000D03*
Y474500D03*
X91300Y528200D03*
X120000Y501500D03*
X129000Y517500D03*
X100000Y512000D03*
X110800Y500600D03*
X100000Y500000D03*
X85000Y506400D03*
X84500Y514400D03*
X129000Y501500D03*
Y509500D03*
X110800Y512600D03*
X120000Y517500D03*
X100000Y506000D03*
X110800Y506600D03*
X120000Y509500D03*
Y523500D03*
X129000D03*
X100000Y519100D03*
X91250Y704700D03*
X97250Y1023500D03*
X95400Y1064100D03*
X91400D03*
X87000Y1063000D03*
X82094Y1112500D03*
X94000Y1514000D03*
X93000Y1518700D03*
X85200Y1515000D03*
X124500Y1524000D03*
X87900Y1523400D03*
X94000Y1562000D03*
Y1550000D03*
X119000Y1529500D03*
X129000Y1562500D03*
X128000Y1568000D03*
X114000Y1546000D03*
X129000Y1542500D03*
X122000Y1546000D03*
Y1538000D03*
X129000Y1549000D03*
X94000Y1556000D03*
X129000Y1535000D03*
X115900Y1569700D03*
X94000Y1568000D03*
X102000D03*
Y1556000D03*
Y1550000D03*
Y1562000D03*
Y1544000D03*
X114000Y1564000D03*
X121800Y1569929D03*
X122000Y1564000D03*
X114000Y1558000D03*
X122000Y1552000D03*
X114000D03*
X122000Y1558000D03*
X111500Y1537500D03*
X129000Y1555500D03*
X116000Y1576000D03*
X122000D03*
Y1584000D03*
X116000D03*
Y1592000D03*
X122000D03*
X116000Y1600000D03*
X122000Y1612000D03*
X116000D03*
X122000Y1600000D03*
X128000Y1606000D03*
X113500Y1605500D03*
X117500Y1669000D03*
X127500D03*
X86000D03*
X97000D03*
X107000D03*
X127000Y1646000D03*
X118000D03*
X117000Y1633500D03*
X127500Y1633000D03*
Y1659500D03*
X117500D03*
X108000Y1646000D03*
X106000Y1634000D03*
X107000Y1659500D03*
X96000Y1646000D03*
X96500Y1634000D03*
X97000Y1659500D03*
X86000Y1646000D03*
Y1634000D03*
Y1659500D03*
X122000Y1685500D03*
X91000Y1685000D03*
X103000D03*
X112500D03*
X98500Y1717000D03*
Y1696500D03*
X99000Y1707000D03*
X117500Y1679000D03*
X125000D03*
X86000D03*
X97500Y1679500D03*
X107500Y1679000D03*
X109500Y1719500D03*
X110000Y1709500D03*
X109500Y1699000D03*
X119500Y1710110D03*
Y1696610D03*
X86500Y1713610D03*
Y1700110D03*
X119500Y1725110D03*
X111500Y1768500D03*
X108500Y1727000D03*
X117500Y1732000D03*
X119500Y1760000D03*
X97500Y1775500D03*
X86500Y1726000D03*
X87000Y1774110D03*
X119500Y1747110D03*
X110500Y1801000D03*
X88500Y1785000D03*
X97500Y1796000D03*
X98000Y1786000D03*
X86500Y1793110D03*
X108268Y1777300D03*
X107768Y1789110D03*
X120000Y1811500D03*
X119500Y1796500D03*
X114000Y1843500D03*
X97000Y1850500D03*
X99500Y1862500D03*
X106500D03*
X114500D03*
X122500D03*
X120500Y1836500D03*
Y1850500D03*
X108500Y1851610D03*
X85100Y1844500D03*
X85700Y1852300D03*
X132000Y1892000D03*
X124500Y1892403D03*
X116948Y1892000D03*
X161600Y445900D03*
X136000Y447000D03*
X135500Y441000D03*
X174500Y432000D03*
X162000D03*
X145500Y427000D03*
X142000Y432000D03*
X169200Y482800D03*
X144000Y493500D03*
Y486182D03*
X137000Y493000D03*
X136500Y485500D03*
X161900Y451600D03*
X162000Y457600D03*
X161900Y463300D03*
X135500Y454000D03*
Y461000D03*
Y474500D03*
Y468000D03*
X173700Y513900D03*
X144000Y517500D03*
Y501500D03*
X173500Y506000D03*
X173600Y498800D03*
X144000Y509500D03*
X157100Y500000D03*
X166100Y527900D03*
X137000Y510000D03*
X137500Y523500D03*
X174900Y523300D03*
X156800Y515400D03*
Y506900D03*
X137000Y501500D03*
X137500Y517500D03*
X159250Y590250D03*
X154600Y581500D03*
X155000Y1120000D03*
Y1125000D03*
Y1130500D03*
X161500Y1227500D03*
X148300Y1465000D03*
X174000Y1515500D03*
X174500Y1509500D03*
Y1503500D03*
X174000Y1522000D03*
X136000Y1528000D03*
X150000Y1570000D03*
X166898Y1567102D03*
X168500Y1526000D03*
X148000Y1564000D03*
X161300Y1563100D03*
X169500Y1561500D03*
X170000Y1548500D03*
X154000Y1564000D03*
X156000Y1570000D03*
X161400Y1543500D03*
X170000Y1555000D03*
X168500Y1533500D03*
X148000Y1542000D03*
Y1528000D03*
Y1558000D03*
X136000Y1548000D03*
Y1555000D03*
Y1562000D03*
Y1536000D03*
Y1542000D03*
Y1568000D03*
X170000Y1541000D03*
X148000Y1550000D03*
X156000Y1576000D03*
X150000D03*
X156000Y1582000D03*
X156500Y1591000D03*
X150500Y1582000D03*
Y1591000D03*
X172000Y1606000D03*
X164000D03*
X156500Y1600000D03*
X156000Y1606000D03*
X150500Y1600000D03*
X176000Y1646000D03*
X166000D03*
X158000D03*
X148000D03*
X176000Y1632000D03*
X178000Y1659500D03*
X167500Y1632500D03*
X170000Y1659500D03*
X149000Y1632500D03*
X159000D03*
X138000Y1634000D03*
X137500Y1659500D03*
X159000D03*
X148500Y1660000D03*
X138000Y1646000D03*
X186500Y498000D03*
X192000Y490000D03*
Y498000D03*
X200300Y498100D03*
X199500Y489400D03*
X188500Y474500D03*
X189900Y467500D03*
Y460500D03*
X190400Y453500D03*
X195000Y467500D03*
X194500Y474500D03*
X195000Y460500D03*
X195500Y453500D03*
X190239Y447449D03*
X195600Y447500D03*
X186500Y513500D03*
Y506000D03*
X192000Y513500D03*
Y506000D03*
X190200Y523400D03*
X201089Y523500D03*
X186500Y519000D03*
X193600Y519100D03*
X200100Y513600D03*
X199800Y506000D03*
X201200Y519200D03*
G54D23*
X80709Y256929D03*
Y266929D03*
Y276929D03*
Y286929D03*
X110709Y256929D03*
Y266929D03*
X100709Y256929D03*
Y266929D03*
X90709Y256929D03*
Y266929D03*
X110709Y276929D03*
Y286929D03*
X100709Y276929D03*
Y286929D03*
X90709Y276929D03*
Y286929D03*
X179606Y256929D03*
Y266929D03*
X169606Y256929D03*
Y266929D03*
X159606Y256929D03*
Y266929D03*
X149606Y256929D03*
Y266929D03*
X179606Y276929D03*
Y286929D03*
X169606Y276929D03*
Y286929D03*
X159606Y276929D03*
Y286929D03*
X149606Y276929D03*
Y286929D03*
G54D11*
X29921Y24803D03*
Y111417D03*
Y458031D03*
Y544646D03*
Y717874D03*
Y804488D03*
X30000Y1164000D03*
X29921Y1250630D03*
Y1423858D03*
Y1510472D03*
Y1857086D03*
Y1943701D03*
G54D19*
X47244Y68110D03*
Y501338D03*
Y761181D03*
Y1207323D03*
Y1467165D03*
Y1900393D03*
G54D20*
X80709Y119409D03*
Y329409D03*
X149606Y119409D03*
Y329409D03*
G54D21*
X80709Y139409D03*
Y309409D03*
X149606Y139409D03*
Y309409D03*
G54D27*
X178937Y1328740D03*
X161417Y1747835D03*
Y1823031D03*
G54D10*
X-222440Y19685D03*
Y1948818D03*
X643700Y19685D03*
Y1948818D03*
G54D18*
X27559Y629921D03*
X17716Y1338583D03*
X27559Y1811023D03*
X179134Y78740D03*
X179133Y570866D03*
X179134Y1161417D03*
G54D14*
X27559Y157480D03*
X179134Y1889764D03*
G54D25*
X58000Y426000D03*
Y408000D03*
X81000Y410500D03*
X91900D03*
X86400D03*
X118000Y424000D03*
Y404000D03*
%LPC*%
G75*
G54D28*
G01X-448201Y-82763D02*
Y-162763D01*
G01Y-118263D02*
X752899D01*
G01X-448201Y-162763D02*
X752899D01*
G01X-452201Y-66763D02*
G02I-12000J0D01*
G01X-457351D02*
G02I-6850J0D01*
G01X-464201Y-82763D02*
Y-50763D01*
G01X-448201Y-66763D02*
X-480201D01*
G01X-448201Y-82763D02*
X752899D01*
G01X-34601D02*
Y-162763D01*
G01X102899Y-82763D02*
Y-162763D01*
G01X217899Y-82763D02*
Y-162763D01*
G01X385399Y-82763D02*
Y-162763D01*
G01X555399Y-82763D02*
Y-162763D01*
G01X752899Y-82763D02*
Y-162763D01*
G01X780899Y-66763D02*
G02I-12000J0D01*
G01X775749D02*
G02I-6850J0D01*
G01X768899Y-82763D02*
Y-50763D01*
G01X784899Y-66763D02*
X752899D01*
G54D29*
G01X-430254Y-152763D02*
Y-135263D01*
G01X-421958D02*
X-430254Y-146055D01*
G01X-420648Y-152763D02*
X-426543Y-141097D01*
G01X-412973Y-152763D02*
Y-135263D01*
X-402929Y-152763D01*
Y-135263D01*
G01X-390451Y-152763D02*
X-392198Y-152471D01*
X-393726Y-151305D01*
X-395036Y-149555D01*
X-395910Y-147513D01*
X-396346Y-145180D01*
Y-142846D01*
X-395910Y-140513D01*
X-395036Y-138471D01*
X-393726Y-136722D01*
X-392198Y-135555D01*
X-390451Y-135263D01*
X-388705Y-135555D01*
X-387176Y-136722D01*
X-385866Y-138471D01*
X-384992Y-140513D01*
X-384556Y-142846D01*
Y-145180D01*
X-384992Y-147513D01*
X-385866Y-149555D01*
X-387176Y-151305D01*
X-388705Y-152471D01*
X-390451Y-152763D01*
G01X-377536D02*
X-368366Y-135263D01*
G01X-377536D02*
X-368366Y-152763D01*
G01X-362001Y-158596D02*
X-348901D01*
G01X-342099Y-152763D02*
Y-135263D01*
X-333803D01*
G01X-336859Y-143721D02*
X-342099D01*
G01X-325910Y-152763D02*
X-320451Y-135263D01*
X-314992Y-152763D01*
G01X-316958Y-146638D02*
X-323945D01*
G01X-307973Y-152763D02*
Y-135263D01*
X-297929Y-152763D01*
Y-135263D01*
G01X-263148Y-136722D02*
X-264458Y-135846D01*
X-265986Y-135263D01*
X-267733D01*
X-269698Y-136138D01*
X-271226Y-137596D01*
X-272318Y-139347D01*
X-273191Y-142263D01*
X-273410Y-144888D01*
X-272973Y-147513D01*
X-272318Y-149263D01*
X-271008Y-151013D01*
X-269479Y-152180D01*
X-267951Y-152763D01*
X-266423D01*
X-264894Y-152180D01*
X-263584Y-151305D01*
X-262492Y-150139D01*
G01X-250451Y-152763D02*
X-252198Y-152471D01*
X-253726Y-151305D01*
X-255036Y-149555D01*
X-255910Y-147513D01*
X-256346Y-145180D01*
Y-142846D01*
X-255910Y-140513D01*
X-255036Y-138471D01*
X-253726Y-136722D01*
X-252198Y-135555D01*
X-250451Y-135263D01*
X-248705Y-135555D01*
X-247176Y-136722D01*
X-245866Y-138471D01*
X-244992Y-140513D01*
X-244556Y-142846D01*
Y-145180D01*
X-244992Y-147513D01*
X-245866Y-149555D01*
X-247176Y-151305D01*
X-248705Y-152471D01*
X-250451Y-152763D01*
G01X-237973D02*
Y-135263D01*
X-227929Y-152763D01*
Y-135263D01*
G01X-215451D02*
Y-152763D01*
G01X-220473Y-135263D02*
X-210429D01*
G01X-202318Y-152763D02*
Y-135263D01*
X-196859D01*
X-195113Y-136138D01*
X-194021Y-137305D01*
X-193584Y-139638D01*
X-194021Y-141972D01*
X-195331Y-143430D01*
X-196859Y-144305D01*
X-202318D01*
G01X-196859D02*
X-193584Y-152763D01*
G01X-180451D02*
X-182198Y-152471D01*
X-183726Y-151305D01*
X-185036Y-149555D01*
X-185910Y-147513D01*
X-186346Y-145180D01*
Y-142846D01*
X-185910Y-140513D01*
X-185036Y-138471D01*
X-183726Y-136722D01*
X-182198Y-135555D01*
X-180451Y-135263D01*
X-178705Y-135555D01*
X-177176Y-136722D01*
X-175866Y-138471D01*
X-174992Y-140513D01*
X-174556Y-142846D01*
Y-145180D01*
X-174992Y-147513D01*
X-175866Y-149555D01*
X-177176Y-151305D01*
X-178705Y-152471D01*
X-180451Y-152763D01*
G01X-167318Y-135263D02*
Y-152763D01*
X-158584D01*
G01X-126205Y-143430D02*
X-125331Y-142555D01*
X-124676Y-141097D01*
X-124239Y-139054D01*
X-124676Y-137305D01*
X-125549Y-136138D01*
X-127078Y-135263D01*
X-132973D01*
Y-152763D01*
X-125768D01*
X-124239Y-151597D01*
X-123366Y-149846D01*
X-122929Y-147805D01*
X-123366Y-145763D01*
X-124676Y-144013D01*
X-126205Y-143430D01*
X-132973D01*
G01X-110451Y-152763D02*
X-112198Y-152471D01*
X-113726Y-151305D01*
X-115036Y-149555D01*
X-115910Y-147513D01*
X-116346Y-145180D01*
Y-142846D01*
X-115910Y-140513D01*
X-115036Y-138471D01*
X-113726Y-136722D01*
X-112198Y-135555D01*
X-110451Y-135263D01*
X-108705Y-135555D01*
X-107176Y-136722D01*
X-105866Y-138471D01*
X-104992Y-140513D01*
X-104556Y-142846D01*
Y-145180D01*
X-104992Y-147513D01*
X-105866Y-149555D01*
X-107176Y-151305D01*
X-108705Y-152471D01*
X-110451Y-152763D01*
G01X-98410D02*
X-92951Y-135263D01*
X-87492Y-152763D01*
G01X-89458Y-146638D02*
X-96445D01*
G01X-79818Y-152763D02*
Y-135263D01*
X-74359D01*
X-72613Y-136138D01*
X-71521Y-137305D01*
X-71084Y-139638D01*
X-71521Y-141972D01*
X-72831Y-143430D01*
X-74359Y-144305D01*
X-79818D01*
G01X-74359D02*
X-71084Y-152763D01*
G01X-62754D02*
Y-135263D01*
X-58388D01*
X-56641Y-136138D01*
X-55331Y-137305D01*
X-54239Y-139054D01*
X-53366Y-141097D01*
X-53148Y-144013D01*
X-53366Y-146930D01*
X-54239Y-148972D01*
X-55331Y-150722D01*
X-56641Y-151888D01*
X-58388Y-152763D01*
X-62754D01*
G01X-282378Y-107763D02*
Y-90263D01*
X-276701Y-104846D01*
X-271024Y-90263D01*
Y-107763D01*
G01X-259201D02*
X-260511Y-107471D01*
X-261821Y-106305D01*
X-262695Y-104263D01*
X-263131Y-101930D01*
X-262695Y-99596D01*
X-261821Y-97555D01*
X-260511Y-96388D01*
X-259201Y-96097D01*
X-257891Y-96388D01*
X-256581Y-97555D01*
X-255708Y-99596D01*
X-255489Y-101930D01*
X-255708Y-104263D01*
X-256581Y-106305D01*
X-257891Y-107471D01*
X-259201Y-107763D01*
G01X-237771Y-90263D02*
Y-107763D01*
G01Y-105139D02*
X-238644Y-106597D01*
X-239955Y-107471D01*
X-241483Y-107763D01*
X-243229Y-107180D01*
X-244539Y-105722D01*
X-245413Y-103972D01*
X-245631Y-101930D01*
X-245413Y-99888D01*
X-244539Y-98138D01*
X-243229Y-96680D01*
X-241483Y-96097D01*
X-239955Y-96388D01*
X-238863Y-96972D01*
X-237771Y-98138D01*
G01X-227476Y-99888D02*
X-220489D01*
X-221144Y-97846D01*
X-222236Y-96680D01*
X-223764Y-96097D01*
X-225293Y-96388D01*
X-226603Y-97263D01*
X-227476Y-99305D01*
X-227913Y-101055D01*
Y-102805D01*
X-227476Y-104555D01*
X-226384Y-106305D01*
X-225074Y-107471D01*
X-223546Y-107763D01*
X-222018Y-107180D01*
X-220489Y-105430D01*
G01X-206701Y-107763D02*
Y-90263D01*
G01X-901Y-152763D02*
Y-135263D01*
X-3521Y-138763D01*
G01Y-152763D02*
X1719D01*
G01X12451Y-138180D02*
X13761Y-136430D01*
X15289Y-135555D01*
X17036Y-135263D01*
X19219Y-135846D01*
X20747Y-137305D01*
X21184Y-139054D01*
X20966Y-140805D01*
X20092Y-142263D01*
X15726Y-145180D01*
X13761Y-147221D01*
X12451Y-150139D01*
X12014Y-152763D01*
X21184D01*
G01X36719D02*
Y-135263D01*
X28640Y-147805D01*
X39558D01*
G01X46796Y-149263D02*
X48105Y-151305D01*
X49852Y-152471D01*
X51817Y-152763D01*
X53564Y-152471D01*
X55311Y-151013D01*
X56402Y-149263D01*
X56621Y-147513D01*
X56184Y-145472D01*
X54656Y-144013D01*
X53127Y-143430D01*
X51162D01*
G01X53127D02*
X54437Y-142555D01*
X55529Y-141097D01*
X55966Y-139347D01*
X55529Y-137596D01*
X54437Y-136138D01*
X52472Y-135263D01*
X50507Y-135555D01*
X48542Y-136722D01*
G01X64296Y-149263D02*
X65605Y-151305D01*
X67352Y-152471D01*
X69317Y-152763D01*
X71064Y-152471D01*
X72811Y-151013D01*
X73902Y-149263D01*
X74121Y-147513D01*
X73684Y-145472D01*
X72156Y-144013D01*
X70627Y-143430D01*
X68662D01*
G01X70627D02*
X71937Y-142555D01*
X73029Y-141097D01*
X73466Y-139347D01*
X73029Y-137596D01*
X71937Y-136138D01*
X69972Y-135263D01*
X68007Y-135555D01*
X66042Y-136722D01*
G01X-14018Y-107763D02*
Y-90263D01*
X-8778D01*
X-7031Y-91138D01*
X-5721Y-93180D01*
X-5284Y-95513D01*
X-5721Y-97846D01*
X-6813Y-99596D01*
X-8778Y-100472D01*
X-14018D01*
G01X12652Y-91722D02*
X11342Y-90846D01*
X9814Y-90263D01*
X8067D01*
X6102Y-91138D01*
X4574Y-92596D01*
X3482Y-94347D01*
X2609Y-97263D01*
X2390Y-99888D01*
X2827Y-102513D01*
X3482Y-104263D01*
X4792Y-106013D01*
X6321Y-107180D01*
X7849Y-107763D01*
X9377D01*
X10906Y-107180D01*
X12216Y-106305D01*
X13308Y-105139D01*
G01X27095Y-98430D02*
X27969Y-97555D01*
X28624Y-96097D01*
X29061Y-94054D01*
X28624Y-92305D01*
X27751Y-91138D01*
X26222Y-90263D01*
X20327D01*
Y-107763D01*
X27532D01*
X29061Y-106597D01*
X29934Y-104846D01*
X30371Y-102805D01*
X29934Y-100763D01*
X28624Y-99013D01*
X27095Y-98430D01*
X20327D01*
G01X36299Y-113596D02*
X49399D01*
G01X55327Y-107763D02*
Y-90263D01*
X65371Y-107763D01*
Y-90263D01*
G01X77849Y-107763D02*
X76102Y-107471D01*
X74574Y-106305D01*
X73264Y-104555D01*
X72390Y-102513D01*
X71954Y-100180D01*
Y-97846D01*
X72390Y-95513D01*
X73264Y-93471D01*
X74574Y-91722D01*
X76102Y-90555D01*
X77849Y-90263D01*
X79595Y-90555D01*
X81124Y-91722D01*
X82434Y-93471D01*
X83308Y-95513D01*
X83744Y-97846D01*
Y-100180D01*
X83308Y-102513D01*
X82434Y-104555D01*
X81124Y-106305D01*
X79595Y-107471D01*
X77849Y-107763D01*
G01X128690Y-90263D02*
X134149Y-107763D01*
X139608Y-90263D01*
G01X156016Y-107763D02*
X147282D01*
Y-90263D01*
X156016D01*
G01X152522Y-98721D02*
X147282D01*
G01X164782Y-107763D02*
Y-90263D01*
X170241D01*
X171987Y-91138D01*
X173079Y-92305D01*
X173516Y-94638D01*
X173079Y-96972D01*
X171769Y-98430D01*
X170241Y-99305D01*
X164782D01*
G01X170241D02*
X173516Y-107763D01*
G01X186649Y-108346D02*
X186212Y-108055D01*
Y-107471D01*
X186649Y-107180D01*
X187086Y-107471D01*
Y-108055D01*
X186649Y-108346D01*
G01X151649Y-152763D02*
Y-135263D01*
X149029Y-138763D01*
G01Y-152763D02*
X154269D01*
G01X163472D02*
Y-135263D01*
X169149Y-149846D01*
X174826Y-135263D01*
Y-152763D01*
G01X340966Y-135263D02*
Y-152763D01*
X332232D01*
G01X323902Y-149263D02*
X322593Y-151305D01*
X320846Y-152471D01*
X318881Y-152763D01*
X317134Y-152471D01*
X315387Y-151013D01*
X314296Y-149263D01*
X314077Y-147513D01*
X314514Y-145472D01*
X316042Y-144013D01*
X317571Y-143430D01*
X319536D01*
G01X317571D02*
X316261Y-142555D01*
X315169Y-141097D01*
X314732Y-139347D01*
X315169Y-137596D01*
X316261Y-136138D01*
X318226Y-135263D01*
X320191Y-135555D01*
X322156Y-136722D01*
G01X307058Y-135263D02*
X301599Y-152763D01*
X296140Y-135263D01*
G01X279296Y-136722D02*
X280606Y-135846D01*
X282134Y-135263D01*
X283881D01*
X285846Y-136138D01*
X287374Y-137596D01*
X288466Y-139347D01*
X289339Y-142263D01*
X289558Y-144888D01*
X289121Y-147513D01*
X288466Y-149263D01*
X287156Y-151013D01*
X285627Y-152180D01*
X284099Y-152763D01*
X282571D01*
X281042Y-152180D01*
X279732Y-151305D01*
X278640Y-150139D01*
G01X261796Y-136722D02*
X263106Y-135846D01*
X264634Y-135263D01*
X266381D01*
X268346Y-136138D01*
X269874Y-137596D01*
X270966Y-139347D01*
X271839Y-142263D01*
X272058Y-144888D01*
X271621Y-147513D01*
X270966Y-149263D01*
X269656Y-151013D01*
X268127Y-152180D01*
X266599Y-152763D01*
X265071D01*
X263542Y-152180D01*
X262232Y-151305D01*
X261140Y-150139D01*
G01X253482Y-90263D02*
Y-107763D01*
X262216D01*
G01X279279D02*
Y-96097D01*
G01Y-98138D02*
X278406Y-96972D01*
X277095Y-96388D01*
X275567Y-96097D01*
X274039Y-96680D01*
X272729Y-97846D01*
X271855Y-99596D01*
X271419Y-101930D01*
X271855Y-104263D01*
X272729Y-106013D01*
X274039Y-107180D01*
X275567Y-107763D01*
X277095Y-107471D01*
X278406Y-106597D01*
X279279Y-105430D01*
G01X288264Y-113013D02*
X289574Y-113596D01*
X291321Y-113013D01*
X292412Y-111847D01*
X293286Y-110388D01*
X294595Y-105722D01*
X297434Y-96097D01*
G01X290447D02*
X294595Y-105722D01*
G01X307074Y-99888D02*
X314061D01*
X313406Y-97846D01*
X312314Y-96680D01*
X310786Y-96097D01*
X309257Y-96388D01*
X307947Y-97263D01*
X307074Y-99305D01*
X306637Y-101055D01*
Y-102805D01*
X307074Y-104555D01*
X308166Y-106305D01*
X309476Y-107471D01*
X311004Y-107763D01*
X312532Y-107180D01*
X314061Y-105430D01*
G01X324792Y-107763D02*
Y-96097D01*
G01Y-98430D02*
X325884Y-97263D01*
X326976Y-96388D01*
X328504Y-96097D01*
X329595Y-96388D01*
X330906Y-97263D01*
G01X342074Y-105722D02*
X343166Y-106888D01*
X344694Y-107763D01*
X346004D01*
X347314Y-107180D01*
X348187Y-106305D01*
X348624Y-105139D01*
X348406Y-103388D01*
X347532Y-102513D01*
X343602Y-100763D01*
X342729Y-98721D01*
X343166Y-97263D01*
X344039Y-96388D01*
X345349Y-96097D01*
X346659Y-96388D01*
X347969Y-97263D01*
G01X404346Y-107763D02*
Y-90263D01*
X408712D01*
X410459Y-91138D01*
X411769Y-92305D01*
X412861Y-94054D01*
X413734Y-96097D01*
X413952Y-99013D01*
X413734Y-101930D01*
X412861Y-103972D01*
X411769Y-105722D01*
X410459Y-106888D01*
X408712Y-107763D01*
X404346D01*
G01X423374Y-99888D02*
X430361D01*
X429706Y-97846D01*
X428614Y-96680D01*
X427086Y-96097D01*
X425557Y-96388D01*
X424247Y-97263D01*
X423374Y-99305D01*
X422937Y-101055D01*
Y-102805D01*
X423374Y-104555D01*
X424466Y-106305D01*
X425776Y-107471D01*
X427304Y-107763D01*
X428832Y-107180D01*
X430361Y-105430D01*
G01X440874Y-105722D02*
X441966Y-106888D01*
X443494Y-107763D01*
X444804D01*
X446114Y-107180D01*
X446987Y-106305D01*
X447424Y-105139D01*
X447206Y-103388D01*
X446332Y-102513D01*
X442402Y-100763D01*
X441529Y-98721D01*
X441966Y-97263D01*
X442839Y-96388D01*
X444149Y-96097D01*
X445459Y-96388D01*
X446769Y-97263D01*
G01X461649Y-96097D02*
Y-107763D01*
G01Y-91430D02*
X461212Y-91138D01*
Y-90555D01*
X461649Y-90263D01*
X462086Y-90555D01*
Y-91138D01*
X461649Y-91430D01*
G01X476092Y-112138D02*
X477621Y-113305D01*
X479367Y-113596D01*
X480895Y-113305D01*
X482206Y-111847D01*
X483079Y-109805D01*
Y-96097D01*
G01Y-98430D02*
X482206Y-97263D01*
X480895Y-96388D01*
X479367Y-96097D01*
X477621Y-96680D01*
X476529Y-97846D01*
X475655Y-99888D01*
X475219Y-101930D01*
X475437Y-103680D01*
X476311Y-105722D01*
X477621Y-107180D01*
X479367Y-107763D01*
X480677Y-107471D01*
X482206Y-106305D01*
X483079Y-105139D01*
G01X492937Y-107763D02*
Y-96097D01*
G01Y-99013D02*
X493811Y-97555D01*
X495121Y-96388D01*
X496867Y-96097D01*
X498395Y-96388D01*
X499706Y-97555D01*
X500361Y-99596D01*
Y-107763D01*
G01X510874Y-99888D02*
X517861D01*
X517206Y-97846D01*
X516114Y-96680D01*
X514586Y-96097D01*
X513057Y-96388D01*
X511747Y-97263D01*
X510874Y-99305D01*
X510437Y-101055D01*
Y-102805D01*
X510874Y-104555D01*
X511966Y-106305D01*
X513276Y-107471D01*
X514804Y-107763D01*
X516332Y-107180D01*
X517861Y-105430D01*
G01X528592Y-107763D02*
Y-96097D01*
G01Y-98430D02*
X529684Y-97263D01*
X530776Y-96388D01*
X532304Y-96097D01*
X533395Y-96388D01*
X534706Y-97263D01*
G01X448096Y-152763D02*
Y-135263D01*
X452462D01*
X454209Y-136138D01*
X455519Y-137305D01*
X456611Y-139054D01*
X457484Y-141097D01*
X457702Y-144013D01*
X457484Y-146930D01*
X456611Y-148972D01*
X455519Y-150722D01*
X454209Y-151888D01*
X452462Y-152763D01*
X448096D01*
G01X470399Y-141097D02*
Y-152763D01*
G01Y-136430D02*
X469962Y-136138D01*
Y-135555D01*
X470399Y-135263D01*
X470836Y-135555D01*
Y-136138D01*
X470399Y-136430D01*
G01X487899Y-152763D02*
X486589Y-152471D01*
X485279Y-151305D01*
X484405Y-149263D01*
X483969Y-146930D01*
X484405Y-144596D01*
X485279Y-142555D01*
X486589Y-141388D01*
X487899Y-141097D01*
X489209Y-141388D01*
X490519Y-142555D01*
X491392Y-144596D01*
X491611Y-146930D01*
X491392Y-149263D01*
X490519Y-151305D01*
X489209Y-152471D01*
X487899Y-152763D01*
G01X575349D02*
Y-135263D01*
X572729Y-138763D01*
G01Y-152763D02*
X577969D01*
G01X588701Y-138180D02*
X590011Y-136430D01*
X591539Y-135555D01*
X593286Y-135263D01*
X595469Y-135846D01*
X596997Y-137305D01*
X597434Y-139054D01*
X597216Y-140805D01*
X596342Y-142263D01*
X591976Y-145180D01*
X590011Y-147221D01*
X588701Y-150139D01*
X588264Y-152763D01*
X597434D01*
G01X606419Y-153346D02*
X614279Y-135263D01*
G01X627849D02*
X626102Y-135846D01*
X624792Y-137305D01*
X623919Y-139054D01*
X623264Y-141388D01*
X623046Y-144013D01*
X623264Y-146638D01*
X623919Y-148972D01*
X624792Y-150722D01*
X626102Y-152180D01*
X627849Y-152763D01*
X629595Y-152180D01*
X630906Y-150722D01*
X631779Y-148972D01*
X632434Y-146638D01*
X632652Y-144013D01*
X632434Y-141388D01*
X631779Y-139054D01*
X630906Y-137305D01*
X629595Y-135846D01*
X627849Y-135263D01*
G01X644912Y-152763D02*
X645349Y-148972D01*
X646004Y-145763D01*
X646877Y-142846D01*
X647969Y-139638D01*
X649716Y-135263D01*
X640982D01*
G01X658919Y-153346D02*
X666779Y-135263D01*
G01X676201Y-138180D02*
X677511Y-136430D01*
X679039Y-135555D01*
X680786Y-135263D01*
X682969Y-135846D01*
X684497Y-137305D01*
X684934Y-139054D01*
X684716Y-140805D01*
X683842Y-142263D01*
X679476Y-145180D01*
X677511Y-147221D01*
X676201Y-150139D01*
X675764Y-152763D01*
X684934D01*
G01X697849Y-135263D02*
X696102Y-135846D01*
X694792Y-137305D01*
X693919Y-139054D01*
X693264Y-141388D01*
X693046Y-144013D01*
X693264Y-146638D01*
X693919Y-148972D01*
X694792Y-150722D01*
X696102Y-152180D01*
X697849Y-152763D01*
X699595Y-152180D01*
X700906Y-150722D01*
X701779Y-148972D01*
X702434Y-146638D01*
X702652Y-144013D01*
X702434Y-141388D01*
X701779Y-139054D01*
X700906Y-137305D01*
X699595Y-135846D01*
X697849Y-135263D01*
G01X715349Y-152763D02*
Y-135263D01*
X712729Y-138763D01*
G01Y-152763D02*
X717969D01*
G01X728701Y-138180D02*
X730011Y-136430D01*
X731539Y-135555D01*
X733286Y-135263D01*
X735469Y-135846D01*
X736997Y-137305D01*
X737434Y-139054D01*
X737216Y-140805D01*
X736342Y-142263D01*
X731976Y-145180D01*
X730011Y-147221D01*
X728701Y-150139D01*
X728264Y-152763D01*
X737434D01*
G01X623046Y-107763D02*
Y-90263D01*
X627412D01*
X629159Y-91138D01*
X630469Y-92305D01*
X631561Y-94054D01*
X632434Y-96097D01*
X632652Y-99013D01*
X632434Y-101930D01*
X631561Y-103972D01*
X630469Y-105722D01*
X629159Y-106888D01*
X627412Y-107763D01*
X623046D01*
G01X649279D02*
Y-96097D01*
G01Y-98138D02*
X648406Y-96972D01*
X647095Y-96388D01*
X645567Y-96097D01*
X644039Y-96680D01*
X642729Y-97846D01*
X641855Y-99596D01*
X641419Y-101930D01*
X641855Y-104263D01*
X642729Y-106013D01*
X644039Y-107180D01*
X645567Y-107763D01*
X647095Y-107471D01*
X648406Y-106597D01*
X649279Y-105430D01*
G01X662849Y-90263D02*
Y-107763D01*
G01X659792Y-96097D02*
X665906D01*
G01X677074Y-99888D02*
X684061D01*
X683406Y-97846D01*
X682314Y-96680D01*
X680786Y-96097D01*
X679257Y-96388D01*
X677947Y-97263D01*
X677074Y-99305D01*
X676637Y-101055D01*
Y-102805D01*
X677074Y-104555D01*
X678166Y-106305D01*
X679476Y-107471D01*
X681004Y-107763D01*
X682532Y-107180D01*
X684061Y-105430D01*
M02*
